FILE_TYPE = MACRO_DRAWING;
SET COLOR_WIRE YELLOW;
SET COLOR_PROP MONO;
SET COLOR_DOT WHITE;
SET COLOR_ARC YELLOW;
SET COLOR_BODY GREEN;
SET COLOR_NOTE MONO;
SET PROP_DISPLAY VALUE;
SET PAGE_NUMBER P137;
FORCEADD RES..1
R 1
(325 3450);
FORCEPROP 1 LAST MATERIAL EMPTY
J 0
(375 3400);
DISPLAY 0.617021 (375 3400);
PAINT RED (375 3400);
FORCEPROP 1 LASTPIN (325 3350) $PN 1
R 1
J 0
(313 3362);
DISPLAY 0.617021 (313 3362);
PAINT MONO (313 3362);
FORCEPROP 1 LAST TOLERANCE 1%
J 0
(375 3500);
DISPLAY 0.617021 (375 3500);
PAINT SKYBLUE (375 3500);
FORCEPROP 1 LASTPIN (325 3550) $PN 2
R 1
J 0
(313 3512);
DISPLAY 0.617021 (313 3512);
PAINT MONO (313 3512);
FORCEPROP 1 LAST VALUE 1.0M
J 2
(525 3550);
DISPLAY 0.617021 (525 3550);
PAINT SKYBLUE (525 3550);
FORCEPROP 1 LAST LOCATION R7C11
J 0
(375 3600);
DISPLAY 0.617021 (375 3600);
PAINT AQUA (375 3600);
FORCEPROP 1 LAST PACK_TYPE 0402
J 0
(375 3300);
DISPLAY 0.617021 (375 3300);
PAINT SKYBLUE (375 3300);
FORCEPROP 1 LAST PART_NUMBER G21796-021
J 0
(375 3350);
DISPLAY 0.617021 (375 3350);
PAINT BLUE (375 3350);
FORCEPROP 1 LAST WATTAGE 1/16W
J 2
(550 3450);
DISPLAY 0.617021 (550 3450);
PAINT SKYBLUE (550 3450);
FORCEPROP 2 LAST ROOM SB
J 0
(375 3650);
PAINT ORANGE (375 3650);
DISPLAY INVISIBLE (375 3650);
FORCEPROP 2 LAST CDS_LOCATION R7C11
J 0
(375 3600);
DISPLAY 0.617021 (375 3600);
PAINT AQUA (375 3600);
DISPLAY INVISIBLE (375 3600);
FORCEPROP 2 LAST $SEC 1
J 0
(375 3650);
DISPLAY 0.936170 (375 3650);
PAINT MONO (375 3650);
DISPLAY INVISIBLE (375 3650);
FORCEPROP 2 LAST CDS_SEC 1
J 0
(375 3650);
DISPLAY 1.404255 (375 3650);
PAINT ORANGE (375 3650);
DISPLAY INVISIBLE (375 3650);
FORCEPROP 2 LAST BOM_COST SB
J 0
(375 3650);
PAINT ORANGE (375 3650);
DISPLAY INVISIBLE (375 3650);
FORCEPROP 2 LAST CDS_LIB mstr_discrete
R 1
J 0
(325 3450);
PAINT ORANGE (325 3450);
DISPLAY INVISIBLE (325 3450);
FORCEPROP 1 LAST PATH I11
R 1
J 0
(175 3400);
DISPLAY 1.319149 (175 3400);
PAINT GREEN (175 3400);
DISPLAY INVISIBLE (175 3400);
FORCEADD OFFPAGE..5
(-3625 3575);
FORCEPROP 2 LAST $XR0 119 
J 0
(-3880 3575);
DISPLAY 0.638298 (-3880 3575);
PAINT MONO (-3880 3575);
FORCEPROP 2 LAST CDS_LIB mstr_standard
J 0
(-3625 3575);
PAINT ORANGE (-3625 3575);
DISPLAY INVISIBLE (-3625 3575);
FORCEPROP 2 LAST PATH I126
J 0
(-3575 3650);
DISPLAY 1.021277 (-3575 3650);
PAINT ORANGE (-3575 3650);
DISPLAY INVISIBLE (-3575 3650);
FORCEPROP 1 LAST OFFPAGE TRUE
J 0
(-3300 3450);
DISPLAY 0.872340 (-3300 3450);
PAINT GREEN (-3300 3450);
DISPLAY INVISIBLE (-3300 3450);
FORCEPROP 1 LAST COMMENT_BODY TRUE
J 0
(-3525 3500);
DISPLAY 0.872340 (-3525 3500);
PAINT GREEN (-3525 3500);
DISPLAY INVISIBLE (-3525 3500);
FORCEADD CONN12_C73564003..1
(-2175 3675);
FORCEPROP 2 LASTPIN (-1825 3725) $PN 4
J 0
(-1815 3735);
DISPLAY 0.617021 (-1815 3735);
PAINT ORANGE (-1815 3735);
FORCEPROP 2 LASTPIN (-1825 3575) $PN 10
J 0
(-1815 3585);
DISPLAY 0.617021 (-1815 3585);
PAINT ORANGE (-1815 3585);
FORCEPROP 2 LASTPIN (-1825 3625) $PN 8
J 0
(-1815 3635);
DISPLAY 0.617021 (-1815 3635);
PAINT ORANGE (-1815 3635);
FORCEPROP 2 LASTPIN (-1825 3675) $PN 6
J 0
(-1815 3685);
DISPLAY 0.617021 (-1815 3685);
PAINT ORANGE (-1815 3685);
FORCEPROP 2 LASTPIN (-2525 3575) $PN 9
J 2
(-2535 3585);
DISPLAY 0.617021 (-2535 3585);
PAINT ORANGE (-2535 3585);
FORCEPROP 2 LASTPIN (-1825 3775) $PN 2
J 0
(-1815 3785);
DISPLAY 0.617021 (-1815 3785);
PAINT ORANGE (-1815 3785);
FORCEPROP 2 LASTPIN (-2525 3625) $PN 7
J 2
(-2535 3635);
DISPLAY 0.617021 (-2535 3635);
PAINT ORANGE (-2535 3635);
FORCEPROP 2 LASTPIN (-2525 3725) $PN 3
J 2
(-2535 3735);
DISPLAY 0.617021 (-2535 3735);
PAINT ORANGE (-2535 3735);
FORCEPROP 2 LASTPIN (-2525 3675) $PN 5
J 2
(-2535 3685);
DISPLAY 0.617021 (-2535 3685);
PAINT ORANGE (-2535 3685);
FORCEPROP 2 LASTPIN (-2525 3775) $PN 1
J 2
(-2535 3785);
DISPLAY 0.617021 (-2535 3785);
PAINT ORANGE (-2535 3785);
FORCEPROP 2 LASTPIN (-2525 3525) $PN 11
J 2
(-2535 3535);
DISPLAY 0.617021 (-2535 3535);
PAINT ORANGE (-2535 3535);
FORCEPROP 2 LASTPIN (-1825 3525) $PN 12
J 0
(-1815 3535);
DISPLAY 0.617021 (-1815 3535);
PAINT ORANGE (-1815 3535);
FORCEPROP 1 LAST MATERIAL CONN
J 0
(-2475 3975);
DISPLAY 0.617021 (-2475 3975);
PAINT SKYBLUE (-2475 3975);
FORCEPROP 1 LAST LOCATION J9G1
J 0
(-2475 4025);
DISPLAY 0.617021 (-2475 4025);
PAINT AQUA (-2475 4025);
FORCEPROP 1 LAST PART_NUMBER C73564-003
J 0
(-2475 3375);
DISPLAY 0.617021 (-2475 3375);
PAINT BLUE (-2475 3375);
FORCEPROP 0 LAST BOM_COST SB
J 0
(-2475 4225);
DISPLAY 1.021277 (-2475 4225);
PAINT ORANGE (-2475 4225);
DISPLAY INVISIBLE (-2475 4225);
FORCEPROP 1 LAST PATH I128
J 0
(-2175 3975);
PAINT GREEN (-2175 3975);
DISPLAY INVISIBLE (-2175 3975);
FORCEPROP 2 LAST CDS_LIB mstr_conn
J 0
(-2175 3675);
PAINT ORANGE (-2175 3675);
DISPLAY INVISIBLE (-2175 3675);
FORCEPROP 2 LAST SEC 1
J 0
(-2475 4075);
DISPLAY 0.680851 (-2475 4075);
PAINT MONO (-2475 4075);
DISPLAY INVISIBLE (-2475 4075);
FORCEPROP 2 LAST SEC_TYPE PIP
J 0
(-2475 4075);
DISPLAY 1.021277 (-2475 4075);
PAINT ORANGE (-2475 4075);
DISPLAY INVISIBLE (-2475 4075);
FORCEPROP 0 LAST ROOM SB
J 0
(-2475 4125);
DISPLAY 1.021277 (-2475 4125);
PAINT ORANGE (-2475 4125);
DISPLAY INVISIBLE (-2475 4125);
FORCEPROP 1 LAST PACK_TYPE PIP
J 0
(-2475 4075);
PAINT SKYBLUE (-2475 4075);
DISPLAY INVISIBLE (-2475 4075);
FORCEADD OFFPAGE..2
(850 3725);
FORCEPROP 2 LAST $XR0 121 
J 0
(1039 3725);
DISPLAY 0.638298 (1039 3725);
PAINT MONO (1039 3725);
FORCEPROP 2 LAST CDS_LIB mstr_standard
J 0
(850 3725);
PAINT ORANGE (850 3725);
DISPLAY INVISIBLE (850 3725);
FORCEPROP 2 LAST PATH I129
J 0
(900 3800);
DISPLAY 1.021277 (900 3800);
PAINT ORANGE (900 3800);
DISPLAY INVISIBLE (900 3800);
FORCEPROP 1 LAST OFFPAGE TRUE
J 0
(1175 3600);
DISPLAY 0.872340 (1175 3600);
PAINT GREEN (1175 3600);
DISPLAY INVISIBLE (1175 3600);
FORCEPROP 1 LAST COMMENT_BODY TRUE
J 0
(805 3630);
DISPLAY 0.872340 (805 3630);
PAINT GREEN (805 3630);
DISPLAY INVISIBLE (805 3630);
FORCEADD RES..2
(-200 4025);
FORCEPROP 1 LAST MATERIAL CHIP
J 0
(-160 3950);
DISPLAY 0.617021 (-160 3950);
PAINT SKYBLUE (-160 3950);
FORCEPROP 1 LASTPIN (-200 3925) $PN 2
J 0
(-195 3935);
DISPLAY 0.617021 (-195 3935);
PAINT MONO (-195 3935);
FORCEPROP 1 LASTPIN (-200 4125) $PN 1
J 0
(-195 4087);
DISPLAY 0.617021 (-195 4087);
PAINT MONO (-195 4087);
FORCEPROP 1 LAST TOLERANCE 1%
J 0
(-155 4050);
DISPLAY 0.617021 (-155 4050);
PAINT SKYBLUE (-155 4050);
FORCEPROP 1 LAST VALUE 20.0K
J 0
(-155 4100);
DISPLAY 0.617021 (-155 4100);
PAINT SKYBLUE (-155 4100);
FORCEPROP 1 LAST WATTAGE 1/16W
J 0
(-160 4000);
DISPLAY 0.617021 (-160 4000);
PAINT SKYBLUE (-160 4000);
FORCEPROP 1 LAST LOCATION R7C10
J 0
(-155 4150);
DISPLAY 0.617021 (-155 4150);
PAINT AQUA (-155 4150);
FORCEPROP 1 LAST PART_NUMBER G21796-040
J 0
(-160 3900);
DISPLAY 0.617021 (-160 3900);
PAINT BLUE (-160 3900);
FORCEPROP 1 LAST PACK_TYPE 0402
J 0
(-160 3850);
DISPLAY 0.617021 (-160 3850);
PAINT SKYBLUE (-160 3850);
FORCEPROP 2 LAST CDS_LIB mstr_discrete
J 0
(-200 4025);
PAINT ORANGE (-200 4025);
DISPLAY INVISIBLE (-200 4025);
FORCEPROP 2 LAST CDS_LOCATION R7C10
J 0
(-155 4150);
DISPLAY 0.617021 (-155 4150);
PAINT AQUA (-155 4150);
DISPLAY INVISIBLE (-155 4150);
FORCEPROP 2 LAST BOM_COST SB
J 0
(-150 4200);
PAINT ORANGE (-150 4200);
DISPLAY INVISIBLE (-150 4200);
FORCEPROP 1 LAST PATH I13
J 0
(-150 4200);
DISPLAY 1.319149 (-150 4200);
PAINT GREEN (-150 4200);
DISPLAY INVISIBLE (-150 4200);
FORCEPROP 2 LAST SEC 1
J 0
(-150 4250);
DISPLAY 0.936170 (-150 4250);
PAINT MONO (-150 4250);
DISPLAY INVISIBLE (-150 4250);
FORCEPROP 0 LAST NO_XNET_CONNECTION 1
J 0
(-150 4275);
PAINT MONO (-150 4275);
DISPLAY INVISIBLE (-150 4275);
FORCEPROP 2 LAST SEC_TYPE 0402
J 0
(-150 4275);
DISPLAY 1.021277 (-150 4275);
PAINT ORANGE (-150 4275);
DISPLAY INVISIBLE (-150 4275);
FORCEPROP 2 LAST ROOM SB
J 0
(-150 4200);
PAINT ORANGE (-150 4200);
DISPLAY INVISIBLE (-150 4200);
FORCEADD RES..1
(-1700 2350);
FORCEPROP 1 LAST VALUE 0.0
J 0
(-1750 2425);
DISPLAY 0.617021 (-1750 2425);
PAINT SKYBLUE (-1750 2425);
FORCEPROP 1 LAST MATERIAL CHIP
J 0
(-1650 2300);
DISPLAY 0.617021 (-1650 2300);
PAINT SKYBLUE (-1650 2300);
FORCEPROP 1 LAST PART_NUMBER G21497-005
J 0
(-1950 2300);
DISPLAY 0.617021 (-1950 2300);
PAINT BLUE (-1950 2300);
FORCEPROP 1 LASTPIN (-1800 2350) $PN 1
J 0
(-1788 2362);
DISPLAY 0.617021 (-1788 2362);
PAINT ORANGE (-1788 2362);
FORCEPROP 1 LASTPIN (-1600 2350) $PN 2
J 0
(-1638 2362);
DISPLAY 0.617021 (-1638 2362);
PAINT ORANGE (-1638 2362);
FORCEPROP 1 LAST TOLERANCE 5%
J 0
(-1650 2425);
DISPLAY 0.617021 (-1650 2425);
PAINT SKYBLUE (-1650 2425);
FORCEPROP 1 LAST WATTAGE 1/16W
J 0
(-1550 2425);
DISPLAY 0.638298 (-1550 2425);
PAINT SKYBLUE (-1550 2425);
FORCEPROP 0 LAST SEC_TYPE 0402
J 0
(-1525 2300);
DISPLAY 0.638298 (-1525 2300);
PAINT SKYBLUE (-1525 2300);
FORCEPROP 1 LAST LOCATION R25W154
J 0
(-1950 2425);
DISPLAY 0.617021 (-1950 2425);
PAINT AQUA (-1950 2425);
FORCEPROP 1 LAST PATH I133
J 0
(-1750 2500);
DISPLAY 0.978723 (-1750 2500);
PAINT WHITE (-1750 2500);
DISPLAY INVISIBLE (-1750 2500);
FORCEPROP 0 LAST CDS_SEC 1
J 0
(-1575 2400);
PAINT MONO (-1575 2400);
DISPLAY INVISIBLE (-1575 2400);
FORCEPROP 1 LAST PACK_TYPE 0402
J 0
(-1450 2200);
DISPLAY 0.978723 (-1450 2200);
PAINT SKYBLUE (-1450 2200);
DISPLAY INVISIBLE (-1450 2200);
FORCEPROP 0 LAST BOM_COST SM_CONTROLLER
J 0
(-1750 2650);
DISPLAY 1.021277 (-1750 2650);
PAINT ORANGE (-1750 2650);
DISPLAY INVISIBLE (-1750 2650);
FORCEPROP 0 LAST ROOM BMC
J 0
(-1750 2550);
DISPLAY 1.021277 (-1750 2550);
PAINT ORANGE (-1750 2550);
DISPLAY INVISIBLE (-1750 2550);
FORCEPROP 2 LAST SEC 1
J 0
(-1750 2550);
DISPLAY 0.680851 (-1750 2550);
PAINT MONO (-1750 2550);
DISPLAY INVISIBLE (-1750 2550);
FORCEPROP 2 LAST CDS_LIB mstr_discrete
J 0
(-1700 2350);
PAINT ORANGE (-1700 2350);
DISPLAY INVISIBLE (-1700 2350);
FORCEPROP 2 LAST CDS_LOCATION R25W154
J 0
(-2100 2350);
DISPLAY 0.617021 (-2100 2350);
PAINT AQUA (-2100 2350);
DISPLAY INVISIBLE (-2100 2350);
FORCEADD OFFPAGE..5
R 2
(-750 2350);
FORCEPROP 2 LAST $XR0 246 
J 0
(-561 2350);
DISPLAY 0.638298 (-561 2350);
PAINT MONO (-561 2350);
FORCEPROP 2 LAST PATH I134
J 0
(-550 2400);
DISPLAY 1.021277 (-550 2400);
PAINT ORANGE (-550 2400);
DISPLAY INVISIBLE (-550 2400);
FORCEPROP 2 LAST CDS_LIB mstr_standard
J 2
(-750 2350);
PAINT MONO (-750 2350);
DISPLAY INVISIBLE (-750 2350);
FORCEPROP 1 LAST OFFPAGE TRUE
J 2
(-1075 2225);
DISPLAY 0.872340 (-1075 2225);
PAINT GREEN (-1075 2225);
DISPLAY INVISIBLE (-1075 2225);
FORCEPROP 1 LAST COMMENT_BODY TRUE
J 2
(-850 2275);
DISPLAY 0.872340 (-850 2275);
PAINT GREEN (-850 2275);
DISPLAY INVISIBLE (-850 2275);
FORCEADD OFFPAGE..1
(-2600 2350);
FORCEPROP 2 LAST $XR0 145 
J 0
(-2882 2350);
DISPLAY 0.638298 (-2882 2350);
PAINT MONO (-2882 2350);
FORCEPROP 2 LAST CDS_LIB mstr_standard
J 0
(-2600 2350);
PAINT MONO (-2600 2350);
DISPLAY INVISIBLE (-2600 2350);
FORCEPROP 2 LAST PATH I135
J 0
(-2550 2425);
DISPLAY 1.021277 (-2550 2425);
PAINT ORANGE (-2550 2425);
DISPLAY INVISIBLE (-2550 2425);
FORCEPROP 2 LAST ROOM BMC
J 0
(-2850 2425);
DISPLAY 1.361702 (-2850 2425);
PAINT ORANGE (-2850 2425);
DISPLAY INVISIBLE (-2850 2425);
FORCEPROP 2 LAST BOM_COST SM_CONTROLLER
J 0
(-2150 2400);
PAINT MONO (-2150 2400);
DISPLAY INVISIBLE (-2150 2400);
FORCEPROP 1 LAST OFFPAGE TRUE
J 0
(-2275 2225);
DISPLAY 0.872340 (-2275 2225);
PAINT GREEN (-2275 2225);
DISPLAY INVISIBLE (-2275 2225);
FORCEPROP 1 LAST COMMENT_BODY TRUE
J 0
(-2475 2250);
DISPLAY 0.872340 (-2475 2250);
PAINT GREEN (-2475 2250);
DISPLAY INVISIBLE (-2475 2250);
FORCEADD OFFPAGE..2
(-1150 3575);
FORCEPROP 2 LAST $XR1 246 
J 0
(-841 3575);
DISPLAY 0.638298 (-841 3575);
PAINT MONO (-841 3575);
FORCEPROP 2 LAST $XR0 146 
J 0
(-961 3575);
DISPLAY 0.638298 (-961 3575);
PAINT MONO (-961 3575);
FORCEPROP 2 LAST PATH I136
J 0
(-975 3650);
DISPLAY 1.021277 (-975 3650);
PAINT ORANGE (-975 3650);
DISPLAY INVISIBLE (-975 3650);
FORCEPROP 2 LAST CDS_LIB mstr_standard
J 0
(-1150 3575);
PAINT MONO (-1150 3575);
DISPLAY INVISIBLE (-1150 3575);
FORCEPROP 1 LAST OFFPAGE TRUE
J 0
(-825 3450);
DISPLAY 0.872340 (-825 3450);
PAINT GREEN (-825 3450);
DISPLAY INVISIBLE (-825 3450);
FORCEPROP 1 LAST COMMENT_BODY TRUE
J 0
(-1195 3480);
DISPLAY 0.872340 (-1195 3480);
PAINT GREEN (-1195 3480);
DISPLAY INVISIBLE (-1195 3480);
FORCEADD CAP_A..1
(-125 3450);
FORCEPROP 1 LASTPIN (-125 3550) $PN 1
J 0
(-115 3530);
DISPLAY 0.617021 (-115 3530);
PAINT MONO (-115 3530);
FORCEPROP 1 LAST VOLTAGE 6.3V
J 0
(-75 3450);
DISPLAY 0.617021 (-75 3450);
PAINT SKYBLUE (-75 3450);
FORCEPROP 1 LAST VALUE 1.0UF
J 0
(-75 3500);
DISPLAY 0.617021 (-75 3500);
PAINT SKYBLUE (-75 3500);
FORCEPROP 1 LAST TOLERANCE 10%
J 0
(-75 3400);
DISPLAY 0.617021 (-75 3400);
PAINT SKYBLUE (-75 3400);
FORCEPROP 1 LAST MATERIAL X6S
J 0
(-75 3350);
DISPLAY 0.617021 (-75 3350);
PAINT SKYBLUE (-75 3350);
FORCEPROP 1 LASTPIN (-125 3350) $PN 2
J 0
(-115 3330);
DISPLAY 0.617021 (-115 3330);
PAINT MONO (-115 3330);
FORCEPROP 1 LAST PACK_TYPE 0402V
J 0
(-75 3250);
DISPLAY 0.617021 (-75 3250);
PAINT SKYBLUE (-75 3250);
FORCEPROP 1 LAST PART_NUMBER D97712-004
J 0
(-75 3300);
DISPLAY 0.617021 (-75 3300);
PAINT BLUE (-75 3300);
FORCEPROP 1 LAST LOCATION C7C19
J 0
(-75 3550);
DISPLAY 0.617021 (-75 3550);
PAINT AQUA (-75 3550);
FORCEPROP 2 LAST CDS_LOCATION C7C19
J 0
(-75 3550);
DISPLAY 0.617021 (-75 3550);
PAINT AQUA (-75 3550);
DISPLAY INVISIBLE (-75 3550);
FORCEPROP 2 LAST CDS_LIB dev_discrete
J 0
(-125 3450);
PAINT ORANGE (-125 3450);
DISPLAY INVISIBLE (-125 3450);
FORCEPROP 2 LAST BOM_COST SB
J 0
(-75 3650);
PAINT ORANGE (-75 3650);
DISPLAY INVISIBLE (-75 3650);
FORCEPROP 2 LAST CDS_SEC 1
J 0
(-75 3600);
PAINT ORANGE (-75 3600);
DISPLAY INVISIBLE (-75 3600);
FORCEPROP 2 LAST SEC_TYPE 0402V
J 0
(-75 3675);
DISPLAY 1.021277 (-75 3675);
PAINT ORANGE (-75 3675);
DISPLAY INVISIBLE (-75 3675);
FORCEPROP 2 LAST SEC 1
J 0
(-75 3650);
DISPLAY 0.936170 (-75 3650);
PAINT MONO (-75 3650);
DISPLAY INVISIBLE (-75 3650);
FORCEPROP 1 LAST PATH I14
J 0
(-75 3600);
DISPLAY 0.978723 (-75 3600);
PAINT WHITE (-75 3600);
DISPLAY INVISIBLE (-75 3600);
FORCEPROP 2 LAST ROOM SB
J 0
(-75 3500);
DISPLAY 1.361702 (-75 3500);
PAINT ORANGE (-75 3500);
DISPLAY INVISIBLE (-75 3500);
FORCEADD RES..1
R 1
(-1250 3300);
FORCEPROP 1 LASTPIN (-1250 3400) $PN 2
J 0
(-1237 3387);
DISPLAY 0.787234 (-1237 3387);
PAINT ORANGE (-1237 3387);
FORCEPROP 1 LAST TOLERANCE 1%
J 0
(-1200 3350);
DISPLAY 0.617021 (-1200 3350);
PAINT SKYBLUE (-1200 3350);
FORCEPROP 1 LAST WATTAGE 1/16W
J 0
(-1200 3300);
DISPLAY 0.617021 (-1200 3300);
PAINT SKYBLUE (-1200 3300);
FORCEPROP 1 LASTPIN (-1250 3200) $PN 1
J 0
(-1237 3187);
DISPLAY 0.787234 (-1237 3187);
PAINT ORANGE (-1237 3187);
FORCEPROP 1 LAST MATERIAL CHIP
J 0
(-1200 3250);
DISPLAY 0.617021 (-1200 3250);
PAINT SKYBLUE (-1200 3250);
FORCEPROP 1 LAST VALUE 4.75K
J 0
(-1200 3400);
DISPLAY 0.617021 (-1200 3400);
PAINT SKYBLUE (-1200 3400);
FORCEPROP 1 LAST LOCATION R25W94
J 0
(-1200 3450);
DISPLAY 0.617021 (-1200 3450);
PAINT AQUA (-1200 3450);
FORCEPROP 1 LAST PACK_TYPE 0402
J 0
(-1200 3150);
DISPLAY 0.617021 (-1200 3150);
PAINT SKYBLUE (-1200 3150);
FORCEPROP 1 LAST PART_NUMBER G21796-072
J 0
(-1200 3200);
DISPLAY 0.617021 (-1200 3200);
PAINT BLUE (-1200 3200);
FORCEPROP 0 LAST CDS_LOCATION R25W94
R 1
J 0
(-1350 3250);
PAINT MONO (-1350 3250);
DISPLAY INVISIBLE (-1350 3250);
FORCEPROP 2 LAST CDS_LIB mstr_discrete
R 1
J 0
(-1250 3300);
PAINT MONO (-1250 3300);
DISPLAY INVISIBLE (-1250 3300);
FORCEPROP 2 LAST BOM_COST SM_CONTROLLER
R 1
J 0
(-1400 3250);
DISPLAY 1.021277 (-1400 3250);
PAINT ORANGE (-1400 3250);
DISPLAY INVISIBLE (-1400 3250);
FORCEPROP 2 LAST ROOM BMC
R 1
J 0
(-1350 3250);
DISPLAY 1.021277 (-1350 3250);
PAINT ORANGE (-1350 3250);
DISPLAY INVISIBLE (-1350 3250);
FORCEPROP 2 LAST SEC_TYPE 0402
R 1
J 0
(-1450 3250);
DISPLAY 1.021277 (-1450 3250);
PAINT ORANGE (-1450 3250);
DISPLAY INVISIBLE (-1450 3250);
FORCEPROP 0 LAST SEC 1
R 1
J 0
(-1350 3250);
PAINT MONO (-1350 3250);
DISPLAY INVISIBLE (-1350 3250);
FORCEPROP 1 LAST PATH I140
R 1
J 0
(-1400 3250);
DISPLAY 0.978723 (-1400 3250);
PAINT WHITE (-1400 3250);
DISPLAY INVISIBLE (-1400 3250);
FORCEADD GND..1
(-1250 3100);
FORCEPROP 3 LASTPIN (-1250 3150) SIG_NAME GND\g
J 0
(-1240 3160);
DISPLAY 0.659574 (-1240 3160);
PAINT MONO (-1240 3160);
DISPLAY INVISIBLE (-1240 3160);
FORCEPROP 1 LAST SIZE 1B
J 0
(-1175 3050);
DISPLAY 0.872340 (-1175 3050);
PAINT AQUA (-1175 3050);
DISPLAY INVISIBLE (-1175 3050);
FORCEPROP 1 LAST VOLTAGE 0.0V
J 0
(-1295 3057);
DISPLAY 0.340426 (-1295 3057);
PAINT GREEN (-1295 3057);
DISPLAY INVISIBLE (-1295 3057);
FORCEPROP 2 LAST CDS_LIB mstr_symbols
J 0
(-1250 3100);
PAINT MONO (-1250 3100);
DISPLAY INVISIBLE (-1250 3100);
FORCEPROP 1 LAST PATH I141
J 0
(-1175 3100);
DISPLAY 0.872340 (-1175 3100);
PAINT AQUA (-1175 3100);
DISPLAY INVISIBLE (-1175 3100);
FORCEPROP 1 LAST BODY_TYPE PLUMBING
J 0
(-1295 3057);
DISPLAY 0.340426 (-1295 3057);
PAINT GREEN (-1295 3057);
DISPLAY INVISIBLE (-1295 3057);
FORCEPROP 1 LAST HDL_POWER GND
J 0
(-1250 3250);
DISPLAY 0.872340 (-1250 3250);
PAINT GREEN (-1250 3250);
DISPLAY INVISIBLE (-1250 3250);
FORCEADD RES..2
R 2
(-1250 4100);
FORCEPROP 1 LAST LOCATION RN8F1
J 2
(-1295 4225);
DISPLAY 0.617021 (-1295 4225);
PAINT AQUA (-1295 4225);
FORCEPROP 1 LASTPIN (-1250 4000) $PN 2
J 2
(-1255 4010);
DISPLAY 0.617021 (-1255 4010);
PAINT ORANGE (-1255 4010);
FORCEPROP 1 LASTPIN (-1250 4200) $PN 1
J 2
(-1255 4162);
DISPLAY 0.617021 (-1255 4162);
PAINT ORANGE (-1255 4162);
FORCEPROP 1 LAST MATERIAL CHIP
J 2
(-1290 4125);
DISPLAY 0.617021 (-1290 4125);
PAINT SKYBLUE (-1290 4125);
FORCEPROP 1 LAST TOLERANCE 1%
J 2
(-1295 4075);
DISPLAY 0.617021 (-1295 4075);
PAINT SKYBLUE (-1295 4075);
FORCEPROP 1 LAST PACK_TYPE 0402
J 2
(-1290 3925);
DISPLAY 0.617021 (-1290 3925);
PAINT SKYBLUE (-1290 3925);
FORCEPROP 1 LAST PART_NUMBER G21796-072
J 2
(-1290 3975);
DISPLAY 0.617021 (-1290 3975);
PAINT BLUE (-1290 3975);
FORCEPROP 1 LAST WATTAGE 1/16W
J 2
(-1290 4025);
DISPLAY 0.617021 (-1290 4025);
PAINT SKYBLUE (-1290 4025);
FORCEPROP 1 LAST VALUE 4.75K
J 2
(-1295 4175);
DISPLAY 0.617021 (-1295 4175);
PAINT SKYBLUE (-1295 4175);
FORCEPROP 0 LAST CDS_LOCATION RN8F1
J 0
(-1275 4275);
PAINT MONO (-1275 4275);
DISPLAY INVISIBLE (-1275 4275);
FORCEPROP 0 LAST CDS_SEC 1
J 0
(-1275 4275);
PAINT MONO (-1275 4275);
DISPLAY INVISIBLE (-1275 4275);
FORCEPROP 2 LAST CDS_LIB mstr_discrete
J 0
(-1250 4100);
PAINT ORANGE (-1250 4100);
DISPLAY INVISIBLE (-1250 4100);
FORCEPROP 2 LAST BOM_COST SM_MEM
J 0
(-1275 4325);
DISPLAY 1.021277 (-1275 4325);
PAINT ORANGE (-1275 4325);
DISPLAY INVISIBLE (-1275 4325);
FORCEPROP 2 LAST SEC_TYPE 0402
J 0
(-1300 4325);
DISPLAY 1.021277 (-1300 4325);
PAINT ORANGE (-1300 4325);
DISPLAY INVISIBLE (-1300 4325);
FORCEPROP 2 LAST ROOM BMC_BOOT_SPI
J 0
(-1275 4275);
DISPLAY 1.021277 (-1275 4275);
PAINT ORANGE (-1275 4275);
DISPLAY INVISIBLE (-1275 4275);
FORCEPROP 2 LAST SEC 1
J 0
(-1300 4325);
DISPLAY 0.680851 (-1300 4325);
PAINT MONO (-1300 4325);
DISPLAY INVISIBLE (-1300 4325);
FORCEPROP 1 LAST PATH I142
J 2
(-1300 4275);
DISPLAY 0.978723 (-1300 4275);
PAINT WHITE (-1300 4275);
DISPLAY INVISIBLE (-1300 4275);
FORCEADD P3V3_STBY..1
(-1250 4400);
FORCEPROP 3 LASTPIN (-1250 4350) SIG_NAME P3V3_STBY\g
J 0
(-1240 4360);
DISPLAY 0.659574 (-1240 4360);
PAINT MONO (-1240 4360);
DISPLAY INVISIBLE (-1240 4360);
FORCEPROP 1 LAST PATH I143
J 0
(-1205 4402);
DISPLAY 0.340426 (-1205 4402);
PAINT GREEN (-1205 4402);
DISPLAY INVISIBLE (-1205 4402);
FORCEPROP 1 LAST SIZE 1B
J 0
(-1205 4422);
DISPLAY 0.340426 (-1205 4422);
PAINT GREEN (-1205 4422);
DISPLAY INVISIBLE (-1205 4422);
FORCEPROP 2 LAST CDS_LIB mstr_symbols
J 0
(-1250 4400);
PAINT MONO (-1250 4400);
DISPLAY INVISIBLE (-1250 4400);
FORCEPROP 1 LAST VOLTAGE 3.3V
J 0
(-1295 4357);
DISPLAY 0.340426 (-1295 4357);
PAINT SKYBLUE (-1295 4357);
DISPLAY INVISIBLE (-1295 4357);
FORCEPROP 1 LAST BODY_TYPE PLUMBING
J 0
(-1295 4357);
DISPLAY 0.340426 (-1295 4357);
PAINT GREEN (-1295 4357);
DISPLAY INVISIBLE (-1295 4357);
FORCEPROP 1 LAST HDL_POWER P3V3_STBY
J 0
(-1550 4275);
DISPLAY 0.872340 (-1550 4275);
PAINT ORANGE (-1550 4275);
DISPLAY INVISIBLE (-1550 4275);
FORCEADD RES..2
(-4500 3450);
FORCEPROP 1 LAST TOLERANCE 1%
J 0
(-4455 3475);
DISPLAY 0.617021 (-4455 3475);
PAINT SKYBLUE (-4455 3475);
FORCEPROP 1 LAST MATERIAL CHIP
J 0
(-4460 3375);
DISPLAY 0.617021 (-4460 3375);
PAINT SKYBLUE (-4460 3375);
FORCEPROP 1 LAST LOCATION R6W2
J 0
(-4455 3575);
DISPLAY 0.617021 (-4455 3575);
PAINT AQUA (-4455 3575);
FORCEPROP 1 LAST VALUE 10.0K
J 0
(-4455 3525);
DISPLAY 0.617021 (-4455 3525);
PAINT SKYBLUE (-4455 3525);
FORCEPROP 1 LAST PACK_TYPE 0402
J 0
(-4460 3275);
DISPLAY 0.617021 (-4460 3275);
PAINT SKYBLUE (-4460 3275);
FORCEPROP 1 LAST PART_NUMBER G21796-016
J 0
(-4460 3325);
DISPLAY 0.617021 (-4460 3325);
PAINT BLUE (-4460 3325);
FORCEPROP 1 LAST WATTAGE 1/16W
J 0
(-4460 3425);
DISPLAY 0.617021 (-4460 3425);
PAINT SKYBLUE (-4460 3425);
FORCEPROP 1 LAST PATH I144
J 0
(-4450 3625);
DISPLAY 0.978723 (-4450 3625);
PAINT WHITE (-4450 3625);
DISPLAY INVISIBLE (-4450 3625);
FORCEPROP 2 LAST ROOM HOT_SWAP
J 0
(-4450 3625);
PAINT MONO (-4450 3625);
DISPLAY INVISIBLE (-4450 3625);
FORCEPROP 2 LAST CDS_LIB mstr_discrete
J 0
(-4500 3450);
PAINT MONO (-4500 3450);
DISPLAY INVISIBLE (-4500 3450);
FORCEPROP 1 LASTPIN (-4500 3350) $PN 2
J 0
(-4495 3360);
DISPLAY 0.787234 (-4495 3360);
PAINT ORANGE (-4495 3360);
DISPLAY INVISIBLE (-4495 3360);
FORCEPROP 1 LASTPIN (-4500 3550) $PN 1
J 0
(-4495 3512);
DISPLAY 0.787234 (-4495 3512);
PAINT ORANGE (-4495 3512);
DISPLAY INVISIBLE (-4495 3512);
FORCEPROP 0 LAST CDS_LOCATION R6W2
J 0
(-4450 3625);
PAINT MONO (-4450 3625);
DISPLAY INVISIBLE (-4450 3625);
FORCEPROP 0 LAST $SEC 1
J 0
(-4450 3625);
PAINT MONO (-4450 3625);
DISPLAY INVISIBLE (-4450 3625);
FORCEPROP 0 LAST CDS_SEC 1
J 0
(-4450 3625);
PAINT MONO (-4450 3625);
DISPLAY INVISIBLE (-4450 3625);
FORCEADD GND..1
(-4500 3250);
FORCEPROP 3 LASTPIN (-4500 3300) SIG_NAME GND\g
J 0
(-4490 3310);
DISPLAY 0.659574 (-4490 3310);
PAINT MONO (-4490 3310);
DISPLAY INVISIBLE (-4490 3310);
FORCEPROP 1 LAST PATH I145
J 0
(-4425 3250);
DISPLAY 0.872340 (-4425 3250);
PAINT AQUA (-4425 3250);
DISPLAY INVISIBLE (-4425 3250);
FORCEPROP 2 LAST CDS_LIB mstr_symbols
J 0
(-4500 3250);
PAINT MONO (-4500 3250);
DISPLAY INVISIBLE (-4500 3250);
FORCEPROP 1 LAST VOLTAGE 0.0V
J 0
(-4545 3207);
DISPLAY 0.340426 (-4545 3207);
PAINT SKYBLUE (-4545 3207);
DISPLAY INVISIBLE (-4545 3207);
FORCEPROP 1 LAST SIZE 1B
J 0
(-4425 3200);
DISPLAY 0.872340 (-4425 3200);
PAINT AQUA (-4425 3200);
DISPLAY INVISIBLE (-4425 3200);
FORCEPROP 1 LAST BODY_TYPE PLUMBING
J 0
(-4545 3207);
DISPLAY 0.340426 (-4545 3207);
PAINT GREEN (-4545 3207);
DISPLAY INVISIBLE (-4545 3207);
FORCEPROP 1 LAST HDL_POWER GND
J 0
(-4500 3400);
DISPLAY 0.872340 (-4500 3400);
PAINT GREEN (-4500 3400);
DISPLAY INVISIBLE (-4500 3400);
FORCEADD P3V3_STBY..1
(-4500 4200);
FORCEPROP 3 LASTPIN (-4500 4150) SIG_NAME P3V3_STBY\g
J 0
(-4490 4160);
DISPLAY 0.659574 (-4490 4160);
PAINT MONO (-4490 4160);
DISPLAY INVISIBLE (-4490 4160);
FORCEPROP 1 LAST PATH I146
J 0
(-4455 4202);
DISPLAY 0.340426 (-4455 4202);
PAINT GREEN (-4455 4202);
DISPLAY INVISIBLE (-4455 4202);
FORCEPROP 2 LAST CDS_LIB mstr_symbols
J 0
(-4500 4200);
PAINT MONO (-4500 4200);
DISPLAY INVISIBLE (-4500 4200);
FORCEPROP 1 LAST SIZE 1B
J 0
(-4455 4222);
DISPLAY 0.340426 (-4455 4222);
PAINT GREEN (-4455 4222);
DISPLAY INVISIBLE (-4455 4222);
FORCEPROP 1 LAST VOLTAGE +3.3V
J 0
(-4300 4350);
DISPLAY 1.021277 (-4300 4350);
PAINT SKYBLUE (-4300 4350);
DISPLAY INVISIBLE (-4300 4350);
FORCEPROP 1 LAST BODY_TYPE PLUMBING
J 0
(-4545 4157);
DISPLAY 0.340426 (-4545 4157);
PAINT GREEN (-4545 4157);
DISPLAY INVISIBLE (-4545 4157);
FORCEPROP 1 LAST HDL_POWER P3V3_STBY
J 0
(-4800 4075);
DISPLAY 0.872340 (-4800 4075);
PAINT ORANGE (-4800 4075);
DISPLAY INVISIBLE (-4800 4075);
FORCEADD OFFPAGE..5
(-3650 3725);
FORCEPROP 2 LAST $XR1 200 
J 0
(-3905 3689);
DISPLAY 0.638298 (-3905 3689);
PAINT MONO (-3905 3689);
FORCEPROP 2 LAST $XR0 146 
J 0
(-3905 3725);
DISPLAY 0.638298 (-3905 3725);
PAINT MONO (-3905 3725);
FORCEPROP 2 LAST PATH I148
J 0
(-3600 3800);
DISPLAY 1.021277 (-3600 3800);
PAINT ORANGE (-3600 3800);
DISPLAY INVISIBLE (-3600 3800);
FORCEPROP 2 LAST CDS_LIB mstr_standard
J 0
(-3650 3725);
PAINT MONO (-3650 3725);
DISPLAY INVISIBLE (-3650 3725);
FORCEPROP 1 LAST OFFPAGE TRUE
J 0
(-3325 3600);
DISPLAY 0.872340 (-3325 3600);
PAINT GREEN (-3325 3600);
DISPLAY INVISIBLE (-3325 3600);
FORCEPROP 1 LAST COMMENT_BODY TRUE
J 0
(-3550 3650);
DISPLAY 0.872340 (-3550 3650);
PAINT GREEN (-3550 3650);
DISPLAY INVISIBLE (-3550 3650);
FORCEADD RES..2
(-4500 3975);
FORCEPROP 1 LAST MATERIAL CHIP
J 0
(-4460 3900);
DISPLAY 0.617021 (-4460 3900);
PAINT SKYBLUE (-4460 3900);
FORCEPROP 1 LAST PART_NUMBER G21796-072
J 0
(-4460 3850);
DISPLAY 0.617021 (-4460 3850);
PAINT BLUE (-4460 3850);
FORCEPROP 1 LAST TOLERANCE 1%
J 0
(-4455 4000);
DISPLAY 0.617021 (-4455 4000);
PAINT SKYBLUE (-4455 4000);
FORCEPROP 1 LAST VALUE 4.75K
J 0
(-4455 4050);
DISPLAY 0.617021 (-4455 4050);
PAINT SKYBLUE (-4455 4050);
FORCEPROP 1 LAST PACK_TYPE 0402
J 0
(-4460 3800);
DISPLAY 0.617021 (-4460 3800);
PAINT SKYBLUE (-4460 3800);
FORCEPROP 1 LASTPIN (-4500 3875) $PN 2
J 0
(-4495 3885);
DISPLAY 0.787234 (-4495 3885);
PAINT ORANGE (-4495 3885);
FORCEPROP 1 LASTPIN (-4500 4075) $PN 1
J 0
(-4495 4037);
DISPLAY 0.787234 (-4495 4037);
PAINT ORANGE (-4495 4037);
FORCEPROP 1 LAST LOCATION R6W1
J 0
(-4455 4100);
DISPLAY 0.617021 (-4455 4100);
PAINT AQUA (-4455 4100);
FORCEPROP 1 LAST WATTAGE 1/16W
J 0
(-4460 3950);
DISPLAY 0.617021 (-4460 3950);
PAINT SKYBLUE (-4460 3950);
FORCEPROP 2 LAST SEC 1
J 0
(-4450 4200);
DISPLAY 0.680851 (-4450 4200);
PAINT MONO (-4450 4200);
DISPLAY INVISIBLE (-4450 4200);
FORCEPROP 2 LAST SEC_TYPE 0402
J 0
(-4450 4200);
DISPLAY 1.021277 (-4450 4200);
PAINT ORANGE (-4450 4200);
DISPLAY INVISIBLE (-4450 4200);
FORCEPROP 2 LAST CDS_LIB mstr_discrete
J 0
(-4500 3975);
PAINT MONO (-4500 3975);
DISPLAY INVISIBLE (-4500 3975);
FORCEPROP 0 LAST BOM_COST SM_THERM
J 0
(-4450 4300);
DISPLAY 1.021277 (-4450 4300);
PAINT ORANGE (-4450 4300);
DISPLAY INVISIBLE (-4450 4300);
FORCEPROP 0 LAST ROOM CPU_FANS
J 0
(-4450 4200);
DISPLAY 1.021277 (-4450 4200);
PAINT ORANGE (-4450 4200);
DISPLAY INVISIBLE (-4450 4200);
FORCEPROP 0 LAST CDS_SEC 1
J 0
(-4450 4150);
PAINT MONO (-4450 4150);
DISPLAY INVISIBLE (-4450 4150);
FORCEPROP 1 LAST PATH I149
J 0
(-4450 4150);
DISPLAY 0.978723 (-4450 4150);
PAINT WHITE (-4450 4150);
DISPLAY INVISIBLE (-4450 4150);
FORCEPROP 0 LAST CDS_LOCATION R6W1
J 0
(-4450 4150);
PAINT MONO (-4450 4150);
DISPLAY INVISIBLE (-4450 4150);
FORCEADD RES..2
R 2
(-275 3450);
FORCEPROP 1 LAST PART_NUMBER G21796-026
J 2
(-315 3325);
DISPLAY 0.617021 (-315 3325);
PAINT BLUE (-315 3325);
FORCEPROP 1 LAST WATTAGE 1/16W
J 2
(-315 3425);
DISPLAY 0.617021 (-315 3425);
PAINT SKYBLUE (-315 3425);
FORCEPROP 1 LAST TOLERANCE 1%
J 2
(-320 3475);
DISPLAY 0.617021 (-320 3475);
PAINT SKYBLUE (-320 3475);
FORCEPROP 1 LAST VALUE 1.00K
J 2
(-320 3525);
DISPLAY 0.617021 (-320 3525);
PAINT SKYBLUE (-320 3525);
FORCEPROP 1 LAST LOCATION R1U63
J 2
(-320 3575);
DISPLAY 0.617021 (-320 3575);
PAINT AQUA (-320 3575);
FORCEPROP 1 LAST MATERIAL CHIP
J 2
(-315 3375);
DISPLAY 0.617021 (-315 3375);
PAINT SKYBLUE (-315 3375);
FORCEPROP 1 LASTPIN (-275 3550) $PN 1
J 2
(-280 3512);
DISPLAY 0.617021 (-280 3512);
PAINT ORANGE (-280 3512);
FORCEPROP 1 LASTPIN (-275 3350) $PN 2
J 2
(-280 3360);
DISPLAY 0.617021 (-280 3360);
PAINT ORANGE (-280 3360);
FORCEPROP 1 LAST PACK_TYPE 0402
J 2
(-315 3275);
DISPLAY 0.617021 (-315 3275);
PAINT SKYBLUE (-315 3275);
FORCEPROP 2 LAST CDS_LIB mstr_discrete
R 3
J 0
(-275 3450);
PAINT ORANGE (-275 3450);
DISPLAY INVISIBLE (-275 3450);
FORCEPROP 2 LAST SEC 1
J 0
(-325 3675);
DISPLAY 0.680851 (-325 3675);
PAINT MONO (-325 3675);
DISPLAY INVISIBLE (-325 3675);
FORCEPROP 2 LAST SEC_TYPE 0402
J 0
(-325 3675);
DISPLAY 1.021277 (-325 3675);
PAINT ORANGE (-325 3675);
DISPLAY INVISIBLE (-325 3675);
FORCEPROP 1 LAST PATH I15
J 2
(-325 3625);
DISPLAY 0.978723 (-325 3625);
PAINT WHITE (-325 3625);
DISPLAY INVISIBLE (-325 3625);
FORCEPROP 2 LAST BOM_COST SB
R 3
J 0
(-475 3650);
PAINT ORANGE (-475 3650);
DISPLAY INVISIBLE (-475 3650);
FORCEPROP 2 LAST ROOM SB
J 2
(-320 3525);
DISPLAY 1.361702 (-320 3525);
PAINT ORANGE (-320 3525);
DISPLAY INVISIBLE (-320 3525);
FORCEADD GND..1
(-275 3125);
FORCEPROP 3 LASTPIN (-275 3175) SIG_NAME GND\g
J 0
(-265 3185);
DISPLAY 0.659574 (-265 3185);
PAINT MONO (-265 3185);
DISPLAY INVISIBLE (-265 3185);
FORCEPROP 2 LAST CDS_LIB mstr_symbols
J 0
(-275 3125);
DISPLAY 1.319149 (-275 3125);
PAINT ORANGE (-275 3125);
DISPLAY INVISIBLE (-275 3125);
FORCEPROP 2 LAST BOM_COST SB
J 0
(-325 3200);
PAINT ORANGE (-325 3200);
DISPLAY INVISIBLE (-325 3200);
FORCEPROP 1 LAST PATH I16
J 0
(-200 3125);
DISPLAY 1.170213 (-200 3125);
PAINT GREEN (-200 3125);
DISPLAY INVISIBLE (-200 3125);
FORCEPROP 1 LAST SIZE 1B
J 0
(-200 3075);
DISPLAY 0.978723 (-200 3075);
PAINT GREEN (-200 3075);
DISPLAY INVISIBLE (-200 3075);
FORCEPROP 2 LAST ROOM WBG_HEADERS_BIOS
J 0
(-650 3200);
PAINT ORANGE (-650 3200);
DISPLAY INVISIBLE (-650 3200);
FORCEPROP 1 LAST VOLTAGE 0
J 0
(-275 3125);
PAINT SKYBLUE (-275 3125);
DISPLAY INVISIBLE (-275 3125);
FORCEPROP 1 LAST BODY_TYPE PLUMBING
J 0
(-320 3082);
DISPLAY 0.340426 (-320 3082);
PAINT GREEN (-320 3082);
DISPLAY INVISIBLE (-320 3082);
FORCEPROP 1 LAST HDL_POWER GND
J 0
(-275 3275);
DISPLAY 0.978723 (-275 3275);
PAINT GREEN (-275 3275);
DISPLAY INVISIBLE (-275 3275);
FORCEADD OFFPAGE..2
(450 1650);
FORCEPROP 2 LAST $XR0 121 
J 0
(639 1650);
DISPLAY 0.638298 (639 1650);
PAINT MONO (639 1650);
FORCEPROP 2 LAST BOM_COST SB
J 0
(650 1700);
PAINT ORANGE (650 1700);
DISPLAY INVISIBLE (650 1700);
FORCEPROP 2 LAST PATH I17
J 0
(650 1700);
PAINT MONO (650 1700);
DISPLAY INVISIBLE (650 1700);
FORCEPROP 2 LAST ROOM WBG_HEADERS_BIOS
J 0
(225 1725);
PAINT ORANGE (225 1725);
DISPLAY INVISIBLE (225 1725);
FORCEPROP 2 LAST CDS_LIB mstr_standard
J 0
(450 1650);
PAINT ORANGE (450 1650);
DISPLAY INVISIBLE (450 1650);
FORCEPROP 1 LAST OFFPAGE TRUE
J 0
(775 1525);
PAINT GREEN (775 1525);
DISPLAY INVISIBLE (775 1525);
FORCEPROP 1 LAST COMMENT_BODY TRUE
J 0
(405 1555);
DISPLAY 1.170213 (405 1555);
PAINT GREEN (405 1555);
DISPLAY INVISIBLE (405 1555);
FORCEADD RES..2
(-300 1900);
FORCEPROP 1 LASTPIN (-300 1800) $PN 2
J 0
(-295 1810);
DISPLAY 0.617021 (-295 1810);
PAINT MONO (-295 1810);
FORCEPROP 1 LASTPIN (-300 2000) $PN 1
J 0
(-295 1962);
DISPLAY 0.617021 (-295 1962);
PAINT MONO (-295 1962);
FORCEPROP 1 LAST MATERIAL CHIP
J 0
(-260 1825);
DISPLAY 0.617021 (-260 1825);
PAINT SKYBLUE (-260 1825);
FORCEPROP 1 LAST TOLERANCE 1%
J 0
(-255 1925);
DISPLAY 0.617021 (-255 1925);
PAINT SKYBLUE (-255 1925);
FORCEPROP 1 LAST LOCATION R3N4
J 0
(-255 2025);
DISPLAY 0.617021 (-255 2025);
PAINT AQUA (-255 2025);
FORCEPROP 1 LAST WATTAGE 1/16W
J 0
(-260 1875);
DISPLAY 0.617021 (-260 1875);
PAINT SKYBLUE (-260 1875);
FORCEPROP 1 LAST PACK_TYPE 0402
J 0
(-260 1725);
DISPLAY 0.617021 (-260 1725);
PAINT SKYBLUE (-260 1725);
FORCEPROP 1 LAST PART_NUMBER G21796-040
J 0
(-260 1775);
DISPLAY 0.617021 (-260 1775);
PAINT BLUE (-260 1775);
FORCEPROP 1 LAST VALUE 20.0K
J 0
(-255 1975);
DISPLAY 0.617021 (-255 1975);
PAINT SKYBLUE (-255 1975);
FORCEPROP 2 LAST CDS_LIB mstr_discrete
J 0
(-300 1900);
PAINT ORANGE (-300 1900);
DISPLAY INVISIBLE (-300 1900);
FORCEPROP 2 LAST CDS_LOCATION R3N4
J 0
(-255 2025);
DISPLAY 0.617021 (-255 2025);
PAINT AQUA (-255 2025);
DISPLAY INVISIBLE (-255 2025);
FORCEPROP 2 LAST BOM_COST SB
J 0
(-250 2075);
PAINT ORANGE (-250 2075);
DISPLAY INVISIBLE (-250 2075);
FORCEPROP 2 LAST CDS_SEC 1
J 0
(-250 2125);
DISPLAY 1.404255 (-250 2125);
PAINT ORANGE (-250 2125);
DISPLAY INVISIBLE (-250 2125);
FORCEPROP 2 LAST $SEC 1
J 0
(-250 2125);
DISPLAY 0.936170 (-250 2125);
PAINT MONO (-250 2125);
DISPLAY INVISIBLE (-250 2125);
FORCEPROP 1 LAST PATH I19
J 0
(-250 2075);
DISPLAY 1.319149 (-250 2075);
PAINT GREEN (-250 2075);
DISPLAY INVISIBLE (-250 2075);
FORCEPROP 0 LAST NO_XNET_CONNECTION 1
J 0
(-250 2150);
PAINT MONO (-250 2150);
DISPLAY INVISIBLE (-250 2150);
FORCEPROP 2 LAST ROOM SB
J 0
(-250 2075);
PAINT ORANGE (-250 2075);
DISPLAY INVISIBLE (-250 2075);
FORCEADD CAP_A..1
(-300 1450);
FORCEPROP 1 LASTPIN (-300 1350) $PN 2
J 0
(-290 1330);
DISPLAY 0.617021 (-290 1330);
PAINT MONO (-290 1330);
FORCEPROP 1 LASTPIN (-300 1550) $PN 1
J 0
(-290 1530);
DISPLAY 0.617021 (-290 1530);
PAINT MONO (-290 1530);
FORCEPROP 1 LAST MATERIAL X6S
J 0
(-250 1350);
DISPLAY 0.617021 (-250 1350);
PAINT SKYBLUE (-250 1350);
FORCEPROP 1 LAST VOLTAGE 6.3V
J 0
(-250 1450);
DISPLAY 0.617021 (-250 1450);
PAINT SKYBLUE (-250 1450);
FORCEPROP 1 LAST PACK_TYPE 0402V
J 0
(-250 1250);
DISPLAY 0.617021 (-250 1250);
PAINT SKYBLUE (-250 1250);
FORCEPROP 1 LAST TOLERANCE 10%
J 0
(-250 1400);
DISPLAY 0.617021 (-250 1400);
PAINT SKYBLUE (-250 1400);
FORCEPROP 1 LAST VALUE 1.0UF
J 0
(-250 1500);
DISPLAY 0.617021 (-250 1500);
PAINT SKYBLUE (-250 1500);
FORCEPROP 1 LAST PART_NUMBER D97712-004
J 0
(-250 1300);
DISPLAY 0.617021 (-250 1300);
PAINT BLUE (-250 1300);
FORCEPROP 1 LAST LOCATION C3N32
J 0
(-250 1550);
DISPLAY 0.617021 (-250 1550);
PAINT AQUA (-250 1550);
FORCEPROP 2 LAST CDS_LIB dev_discrete
J 0
(-300 1450);
PAINT ORANGE (-300 1450);
DISPLAY INVISIBLE (-300 1450);
FORCEPROP 1 LAST PATH I20
J 0
(-250 1600);
DISPLAY 0.978723 (-250 1600);
PAINT WHITE (-250 1600);
DISPLAY INVISIBLE (-250 1600);
FORCEPROP 2 LAST SEC 1
J 0
(-250 1650);
DISPLAY 0.936170 (-250 1650);
PAINT MONO (-250 1650);
DISPLAY INVISIBLE (-250 1650);
FORCEPROP 2 LAST SEC_TYPE 0402V
J 0
(-250 1675);
DISPLAY 1.021277 (-250 1675);
PAINT ORANGE (-250 1675);
DISPLAY INVISIBLE (-250 1675);
FORCEPROP 2 LAST CDS_SEC 1
J 0
(-250 1600);
PAINT ORANGE (-250 1600);
DISPLAY INVISIBLE (-250 1600);
FORCEPROP 2 LAST BOM_COST SB
J 0
(-250 1600);
PAINT ORANGE (-250 1600);
DISPLAY INVISIBLE (-250 1600);
FORCEPROP 2 LAST CDS_LOCATION C3N32
J 0
(-250 1550);
DISPLAY 0.617021 (-250 1550);
PAINT AQUA (-250 1550);
DISPLAY INVISIBLE (-250 1550);
FORCEPROP 2 LAST ROOM SB
J 0
(-250 1600);
PAINT ORANGE (-250 1600);
DISPLAY INVISIBLE (-250 1600);
FORCEADD GND..1
(-300 1250);
FORCEPROP 3 LASTPIN (-300 1300) SIG_NAME GND\g
J 0
(-290 1310);
DISPLAY 0.659574 (-290 1310);
PAINT MONO (-290 1310);
DISPLAY INVISIBLE (-290 1310);
FORCEPROP 2 LAST CDS_LIB mstr_symbols
J 0
(-300 1250);
PAINT ORANGE (-300 1250);
DISPLAY INVISIBLE (-300 1250);
FORCEPROP 2 LAST BOM_COST SB
J 0
(-350 1325);
PAINT ORANGE (-350 1325);
DISPLAY INVISIBLE (-350 1325);
FORCEPROP 1 LAST PATH I21
J 0
(-225 1250);
DISPLAY 1.170213 (-225 1250);
PAINT GREEN (-225 1250);
DISPLAY INVISIBLE (-225 1250);
FORCEPROP 1 LAST SIZE 1B
J 0
(-225 1200);
DISPLAY 1.170213 (-225 1200);
PAINT GREEN (-225 1200);
DISPLAY INVISIBLE (-225 1200);
FORCEPROP 2 LAST ROOM WBG_HEADERS_BIOS
J 0
(-675 1325);
PAINT ORANGE (-675 1325);
DISPLAY INVISIBLE (-675 1325);
FORCEPROP 1 LAST VOLTAGE 0
J 0
(-300 1250);
PAINT SKYBLUE (-300 1250);
DISPLAY INVISIBLE (-300 1250);
FORCEPROP 1 LAST BODY_TYPE PLUMBING
J 0
(-345 1207);
DISPLAY 0.340426 (-345 1207);
PAINT GREEN (-345 1207);
DISPLAY INVISIBLE (-345 1207);
FORCEPROP 1 LAST HDL_POWER GND
J 0
(-300 1400);
DISPLAY 1.170213 (-300 1400);
PAINT GREEN (-300 1400);
DISPLAY INVISIBLE (-300 1400);
FORCEADD RES..2
(-2650 4225);
FORCEPROP 1 LASTPIN (-2650 4125) $PN 2
J 0
(-2645 4135);
DISPLAY 0.617021 (-2645 4135);
PAINT ORANGE (-2645 4135);
FORCEPROP 1 LAST LOCATION R7C13
J 0
(-2605 4350);
DISPLAY 0.617021 (-2605 4350);
PAINT AQUA (-2605 4350);
FORCEPROP 1 LAST PACK_TYPE 0402
J 0
(-2610 4050);
DISPLAY 0.617021 (-2610 4050);
PAINT SKYBLUE (-2610 4050);
FORCEPROP 1 LAST TOLERANCE 1%
J 0
(-2605 4250);
DISPLAY 0.617021 (-2605 4250);
PAINT SKYBLUE (-2605 4250);
FORCEPROP 1 LAST VALUE 10.0K
J 0
(-2605 4300);
DISPLAY 0.617021 (-2605 4300);
PAINT SKYBLUE (-2605 4300);
FORCEPROP 1 LAST WATTAGE 1/16W
J 0
(-2610 4200);
DISPLAY 0.617021 (-2610 4200);
PAINT SKYBLUE (-2610 4200);
FORCEPROP 1 LAST PART_NUMBER G21796-016
J 0
(-2610 4100);
DISPLAY 0.617021 (-2610 4100);
PAINT BLUE (-2610 4100);
FORCEPROP 1 LASTPIN (-2650 4325) $PN 1
J 0
(-2645 4287);
DISPLAY 0.617021 (-2645 4287);
PAINT ORANGE (-2645 4287);
FORCEPROP 1 LAST MATERIAL CHIP
J 0
(-2610 4150);
DISPLAY 0.617021 (-2610 4150);
PAINT SKYBLUE (-2610 4150);
FORCEPROP 2 LAST ROOM SB
J 0
(-2605 4300);
DISPLAY 1.361702 (-2605 4300);
PAINT ORANGE (-2605 4300);
DISPLAY INVISIBLE (-2605 4300);
FORCEPROP 1 LAST PATH I67
J 0
(-2600 4400);
DISPLAY 0.978723 (-2600 4400);
PAINT WHITE (-2600 4400);
DISPLAY INVISIBLE (-2600 4400);
FORCEPROP 2 LAST SEC 1
J 0
(-2600 4450);
PAINT MONO (-2600 4450);
DISPLAY INVISIBLE (-2600 4450);
FORCEPROP 2 LAST BOM_COST SB
J 0
(-2600 4400);
PAINT ORANGE (-2600 4400);
DISPLAY INVISIBLE (-2600 4400);
FORCEPROP 2 LAST SEC_TYPE 0402
J 0
(-2600 4450);
DISPLAY 1.021277 (-2600 4450);
PAINT ORANGE (-2600 4450);
DISPLAY INVISIBLE (-2600 4450);
FORCEPROP 2 LAST CDS_LOCATION R7C13
J 0
(-2605 4350);
DISPLAY 0.617021 (-2605 4350);
PAINT AQUA (-2605 4350);
DISPLAY INVISIBLE (-2605 4350);
FORCEPROP 2 LAST CDS_LIB mstr_discrete
J 0
(-2650 4225);
PAINT MONO (-2650 4225);
DISPLAY INVISIBLE (-2650 4225);
FORCEADD P3V3_STBY..1
(-2650 4450);
FORCEPROP 3 LASTPIN (-2650 4400) SIG_NAME P3V3_STBY\g
J 0
(-2640 4410);
DISPLAY 0.659574 (-2640 4410);
PAINT MONO (-2640 4410);
DISPLAY INVISIBLE (-2640 4410);
FORCEPROP 1 LAST SIZE 1B
J 0
(-2605 4472);
DISPLAY 0.340426 (-2605 4472);
PAINT GREEN (-2605 4472);
DISPLAY INVISIBLE (-2605 4472);
FORCEPROP 2 LAST CDS_LIB mstr_symbols
J 0
(-2650 4450);
PAINT MONO (-2650 4450);
DISPLAY INVISIBLE (-2650 4450);
FORCEPROP 1 LAST VOLTAGE 3.3V
J 0
(-2695 4407);
DISPLAY 0.340426 (-2695 4407);
PAINT SKYBLUE (-2695 4407);
DISPLAY INVISIBLE (-2695 4407);
FORCEPROP 1 LAST PATH I68
J 0
(-2605 4452);
DISPLAY 0.340426 (-2605 4452);
PAINT GREEN (-2605 4452);
DISPLAY INVISIBLE (-2605 4452);
FORCEPROP 1 LAST BODY_TYPE PLUMBING
J 0
(-2695 4407);
DISPLAY 0.340426 (-2695 4407);
PAINT GREEN (-2695 4407);
DISPLAY INVISIBLE (-2695 4407);
FORCEPROP 1 LAST HDL_POWER P3V3_STBY
J 0
(-2950 4325);
DISPLAY 0.872340 (-2950 4325);
PAINT ORANGE (-2950 4325);
DISPLAY INVISIBLE (-2950 4325);
FORCEADD RES..2
(-3150 3275);
FORCEPROP 1 LASTPIN (-3150 3375) $PN 1
J 0
(-3145 3337);
DISPLAY 0.617021 (-3145 3337);
PAINT ORANGE (-3145 3337);
FORCEPROP 1 LASTPIN (-3150 3175) $PN 2
J 0
(-3145 3185);
DISPLAY 0.617021 (-3145 3185);
PAINT ORANGE (-3145 3185);
FORCEPROP 1 LAST WATTAGE 1/16W
J 0
(-3110 3250);
DISPLAY 0.617021 (-3110 3250);
PAINT SKYBLUE (-3110 3250);
FORCEPROP 1 LAST PACK_TYPE 0402
J 0
(-3110 3100);
DISPLAY 0.617021 (-3110 3100);
PAINT SKYBLUE (-3110 3100);
FORCEPROP 1 LAST MATERIAL CHIP
J 0
(-3110 3200);
DISPLAY 0.617021 (-3110 3200);
PAINT SKYBLUE (-3110 3200);
FORCEPROP 1 LAST PART_NUMBER G21796-026
J 0
(-3110 3150);
DISPLAY 0.617021 (-3110 3150);
PAINT BLUE (-3110 3150);
FORCEPROP 1 LAST VALUE 1.00K
J 0
(-3105 3350);
DISPLAY 0.617021 (-3105 3350);
PAINT SKYBLUE (-3105 3350);
FORCEPROP 1 LAST LOCATION R1U64
J 0
(-3105 3400);
DISPLAY 0.617021 (-3105 3400);
PAINT AQUA (-3105 3400);
FORCEPROP 1 LAST TOLERANCE 1%
J 0
(-3105 3300);
DISPLAY 0.617021 (-3105 3300);
PAINT SKYBLUE (-3105 3300);
FORCEPROP 2 LAST ROOM SB
J 0
(-3105 3350);
DISPLAY 1.361702 (-3105 3350);
PAINT ORANGE (-3105 3350);
DISPLAY INVISIBLE (-3105 3350);
FORCEPROP 2 LAST BOM_COST SB
R 3
J 0
(-2975 3225);
PAINT ORANGE (-2975 3225);
DISPLAY INVISIBLE (-2975 3225);
FORCEPROP 2 LAST SEC_TYPE 0402
J 0
(-3100 3500);
DISPLAY 1.021277 (-3100 3500);
PAINT ORANGE (-3100 3500);
DISPLAY INVISIBLE (-3100 3500);
FORCEPROP 2 LAST SEC 1
J 0
(-3100 3500);
DISPLAY 0.680851 (-3100 3500);
PAINT MONO (-3100 3500);
DISPLAY INVISIBLE (-3100 3500);
FORCEPROP 1 LAST PATH I69
J 0
(-3100 3450);
DISPLAY 0.978723 (-3100 3450);
PAINT WHITE (-3100 3450);
DISPLAY INVISIBLE (-3100 3450);
FORCEPROP 2 LAST CDS_LIB mstr_discrete
R 3
J 0
(-3150 3275);
PAINT MONO (-3150 3275);
DISPLAY INVISIBLE (-3150 3275);
FORCEADD GND..1
(-3150 3000);
FORCEPROP 3 LASTPIN (-3150 3050) SIG_NAME GND\g
J 0
(-3140 3060);
DISPLAY 0.659574 (-3140 3060);
PAINT MONO (-3140 3060);
DISPLAY INVISIBLE (-3140 3060);
FORCEPROP 1 LAST VOLTAGE 0
J 0
(-3150 3000);
PAINT SKYBLUE (-3150 3000);
DISPLAY INVISIBLE (-3150 3000);
FORCEPROP 2 LAST ROOM WBG_HEADERS_BIOS
J 0
(-3525 3075);
PAINT ORANGE (-3525 3075);
DISPLAY INVISIBLE (-3525 3075);
FORCEPROP 2 LAST BOM_COST SB
J 0
(-3200 3075);
PAINT ORANGE (-3200 3075);
DISPLAY INVISIBLE (-3200 3075);
FORCEPROP 1 LAST PATH I70
J 0
(-3075 3000);
DISPLAY 0.872340 (-3075 3000);
PAINT AQUA (-3075 3000);
DISPLAY INVISIBLE (-3075 3000);
FORCEPROP 1 LAST SIZE 1B
J 0
(-3075 2950);
DISPLAY 0.851064 (-3075 2950);
PAINT GREEN (-3075 2950);
DISPLAY INVISIBLE (-3075 2950);
FORCEPROP 2 LAST CDS_LIB mstr_symbols
J 0
(-3150 3000);
PAINT MONO (-3150 3000);
DISPLAY INVISIBLE (-3150 3000);
FORCEPROP 1 LAST BODY_TYPE PLUMBING
J 0
(-3195 2957);
DISPLAY 0.340426 (-3195 2957);
PAINT GREEN (-3195 2957);
DISPLAY INVISIBLE (-3195 2957);
FORCEPROP 1 LAST HDL_POWER GND
J 0
(-3150 3150);
DISPLAY 0.851064 (-3150 3150);
PAINT GREEN (-3150 3150);
DISPLAY INVISIBLE (-3150 3150);
FORCEADD P3V3_RTC_STBY..1
(-200 4225);
FORCEPROP 3 LASTPIN (-200 4175) SIG_NAME P3V3_RTC_STBY\g
J 0
(-190 4185);
DISPLAY 0.659574 (-190 4185);
PAINT MONO (-190 4185);
DISPLAY INVISIBLE (-190 4185);
FORCEPROP 1 LAST PATH I78
J 0
(-150 4250);
DISPLAY 0.872340 (-150 4250);
PAINT AQUA (-150 4250);
DISPLAY INVISIBLE (-150 4250);
FORCEPROP 2 LAST CDS_LIB mstr_symbols
J 0
(-200 4225);
PAINT ORANGE (-200 4225);
DISPLAY INVISIBLE (-200 4225);
FORCEPROP 2 LAST BOM_COST SB
J 0
(-200 4375);
PAINT MONO (-200 4375);
DISPLAY INVISIBLE (-200 4375);
FORCEPROP 2 LAST ROOM SB_DECOUPLING
J 0
(-200 4325);
DISPLAY 1.361702 (-200 4325);
PAINT WHITE (-200 4325);
DISPLAY INVISIBLE (-200 4325);
FORCEPROP 1 LAST VOLTAGE 3.3V
J 0
(-245 4182);
DISPLAY 0.340426 (-245 4182);
PAINT SKYBLUE (-245 4182);
DISPLAY INVISIBLE (-245 4182);
FORCEPROP 1 LAST BODY_TYPE PLUMBING
J 0
(-245 4182);
DISPLAY 0.340426 (-245 4182);
PAINT GREEN (-245 4182);
DISPLAY INVISIBLE (-245 4182);
FORCEPROP 1 LAST HDL_POWER P3V3_RTC_STBY
J 1
(-200 4275);
DISPLAY 0.872340 (-200 4275);
PAINT GREEN (-200 4275);
DISPLAY INVISIBLE (-200 4275);
FORCEADD P3V3_RTC_STBY..1
(-300 2150);
FORCEPROP 3 LASTPIN (-300 2100) SIG_NAME P3V3_RTC_STBY\g
J 0
(-290 2110);
DISPLAY 0.659574 (-290 2110);
PAINT MONO (-290 2110);
DISPLAY INVISIBLE (-290 2110);
FORCEPROP 2 LAST BOM_COST SB
J 0
(-300 2300);
PAINT MONO (-300 2300);
DISPLAY INVISIBLE (-300 2300);
FORCEPROP 2 LAST CDS_LIB mstr_symbols
J 0
(-300 2150);
PAINT ORANGE (-300 2150);
DISPLAY INVISIBLE (-300 2150);
FORCEPROP 1 LAST PATH I79
J 0
(-250 2175);
DISPLAY 0.872340 (-250 2175);
PAINT AQUA (-250 2175);
DISPLAY INVISIBLE (-250 2175);
FORCEPROP 2 LAST ROOM SB_DECOUPLING
J 0
(-300 2250);
DISPLAY 1.361702 (-300 2250);
PAINT WHITE (-300 2250);
DISPLAY INVISIBLE (-300 2250);
FORCEPROP 1 LAST VOLTAGE 3.3V
J 0
(-345 2107);
DISPLAY 0.340426 (-345 2107);
PAINT SKYBLUE (-345 2107);
DISPLAY INVISIBLE (-345 2107);
FORCEPROP 1 LAST BODY_TYPE PLUMBING
J 0
(-345 2107);
DISPLAY 0.340426 (-345 2107);
PAINT GREEN (-345 2107);
DISPLAY INVISIBLE (-345 2107);
FORCEPROP 1 LAST HDL_POWER P3V3_RTC_STBY
J 1
(-300 2200);
DISPLAY 0.872340 (-300 2200);
PAINT GREEN (-300 2200);
DISPLAY INVISIBLE (-300 2200);
FORCEADD DESIGN_NOTE..1
(550 4375);
FORCEPROP 0 LAST L1 CMOS CLEAR JUMPER
J 0
(350 4250);
DISPLAY 1.021277 (350 4250);
PAINT ORANGE (350 4250);
FORCEPROP 2 LAST CDS_LIB mstr_symbols
J 0
(550 4375);
PAINT ORANGE (550 4375);
DISPLAY INVISIBLE (550 4375);
FORCEPROP 1 LAST COMMENT_BODY TRUE
J 0
(575 4475);
DISPLAY 0.978723 (575 4475);
PAINT ORANGE (575 4475);
DISPLAY INVISIBLE (575 4475);
FORCEADD DESIGN_NOTE..1
(-2150 3000);
FORCEPROP 0 LAST L1 BMC ENABLE
J 0
(-2350 2875);
DISPLAY 1.021277 (-2350 2875);
PAINT ORANGE (-2350 2875);
FORCEPROP 2 LAST CDS_LIB mstr_symbols
J 0
(-2150 3000);
PAINT MONO (-2150 3000);
DISPLAY INVISIBLE (-2150 3000);
FORCEPROP 1 LAST COMMENT_BODY TRUE
J 0
(-2125 3100);
DISPLAY 0.978723 (-2125 3100);
PAINT ORANGE (-2125 3100);
DISPLAY INVISIBLE (-2125 3100);
FORCEADD DESIGN_NOTE..1
(-3975 4475);
FORCEPROP 0 LAST L1 UVP INBN
J 0
(-4175 4350);
DISPLAY 1.021277 (-4175 4350);
PAINT ORANGE (-4175 4350);
FORCEPROP 2 LAST CDS_LIB mstr_symbols
J 0
(-3975 4475);
PAINT MONO (-3975 4475);
DISPLAY INVISIBLE (-3975 4475);
FORCEPROP 1 LAST COMMENT_BODY TRUE
J 0
(-3950 4575);
DISPLAY 0.978723 (-3950 4575);
PAINT ORANGE (-3950 4575);
DISPLAY INVISIBLE (-3950 4575);
FORCEADD DNS..2
(330 3445);
PAINT RED (330 3445);
FORCEPROP 2 LAST CDS_LIB mstr_misc
J 0
(330 3445);
PAINT ORANGE (330 3445);
DISPLAY INVISIBLE (330 3445);
FORCEPROP 1 LAST COMMENT_BODY TRUE
R 1
J 0
(405 3220);
DISPLAY 0.872340 (405 3220);
PAINT GREEN (405 3220);
DISPLAY INVISIBLE (405 3220);
FORCEADD INTEL_CORP_BPAGE..1
(2650 500);
FORCEPROP 1 LAST CDS_CON_LAST_MODIFIED Fri Jun 16 17:48:52 2017
J 0
(1225 825);
PAINT ORANGE (1225 825);
DISPLAY INVISIBLE (1225 825);
FORCEPROP 1 LAST CUSTOM_TXT_CDS <CURRENT_DESIGN_SHEET> OF <TOTAL_DESIGN_SHEETS>
J 0
(2150 525);
PAINT ORANGE (2150 525);
FORCEPROP 1 LAST CUSTOM_TXT_CDS <CON_LAST_MODIFIED>
J 0
(-1350 600);
PAINT ORANGE (-1350 600);
FORCEPROP 2 LAST CUSTOM_TXT_CDS <XR_PAGE_TITLE>
J 0
(-5240 5750);
DISPLAY 0.638298 (-5240 5750);
PAINT PINK (-5240 5750);
DISPLAY INVISIBLE (-5240 5750);
FORCEPROP 1 LAST SCH_TITLE LBG HEADERS (3/3)
J 0
(-5300 550);
DISPLAY 1.212766 (-5300 550);
PAINT ORANGE (-5300 550);
FORCEPROP 2 LAST PAGE_BORDER TRUE
J 0
(-5240 5750);
DISPLAY 0.851064 (-5240 5750);
PAINT PINK (-5240 5750);
DISPLAY INVISIBLE (-5240 5750);
FORCEPROP 2 LAST BOM_COST SB
J 0
(-5225 5800);
PAINT MONO (-5225 5800);
DISPLAY INVISIBLE (-5225 5800);
FORCEPROP 2 LAST CDS_LIB mstr_symbols
J 0
(2650 500);
PAINT MONO (2650 500);
DISPLAY INVISIBLE (2650 500);
FORCEPROP 2 LAST ROOM WBG_HEADERS_BIOS
J 0
(-5225 5800);
PAINT MONO (-5225 5800);
DISPLAY INVISIBLE (-5225 5800);
FORCEPROP 1 LAST COMMENT_BODY TRUE
J 0
(2662 512);
DISPLAY 0.468085 (2662 512);
PAINT GREEN (2662 512);
DISPLAY INVISIBLE (2662 512);
FORCEPROP 2 LAST CDS_XR_PAGE_TITLE CR-137 : @BASEBOARD_FAB2_LIB.BASEBOARD_FAB2(SCH_1):PAGE137
J 0
(-5240 5750);
DISPLAY 0.638298 (-5240 5750);
PAINT PINK (-5240 5750);
DISPLAY INVISIBLE (-5240 5750);
FORCEADD BOM_NOTE..1
(-4975 2350);
FORCEPROP 0 LAST L1 4 JUMPER HEADERS ADDED (IPN 634479-007) IN MOD FILE
J 0
(-5125 2200);
DISPLAY 0.808511 (-5125 2200);
PAINT ORANGE (-5125 2200);
FORCEPROP 2 LAST CDS_LIB mstr_symbols
J 0
(-4975 2350);
PAINT ORANGE (-4975 2350);
DISPLAY INVISIBLE (-4975 2350);
FORCEPROP 1 LAST COMMENT_BODY TRUE
J 0
(-4950 2450);
DISPLAY 0.978723 (-4950 2450);
PAINT ORANGE (-4950 2450);
DISPLAY INVISIBLE (-4950 2450);
FORCEADD DESIGN_NOTE..1
(-3975 3375);
FORCEPROP 0 LAST L1 IE DEBUG
J 0
(-4175 3250);
DISPLAY 1.021277 (-4175 3250);
PAINT ORANGE (-4175 3250);
FORCEPROP 2 LAST CDS_LIB mstr_symbols
J 0
(-3975 3375);
PAINT MONO (-3975 3375);
DISPLAY INVISIBLE (-3975 3375);
FORCEPROP 1 LAST COMMENT_BODY TRUE
J 0
(-3950 3475);
DISPLAY 0.978723 (-3950 3475);
PAINT ORANGE (-3950 3475);
DISPLAY INVISIBLE (-3950 3475);
FORCEADD CAD_NOTE..1
(-2975 2675);
FORCEPROP 0 LAST L1 PLACE TO THE RIGHT OF OTHER 2X6 HEADER
J 0
(-3125 2550);
DISPLAY 1.021277 (-3125 2550);
PAINT ORANGE (-3125 2550);
FORCEPROP 2 LAST CDS_LIB mstr_symbols
J 0
(-2975 2675);
PAINT ORANGE (-2975 2675);
DISPLAY INVISIBLE (-2975 2675);
FORCEPROP 1 LAST COMMENT_BODY TRUE
J 0
(-2950 2775);
DISPLAY 0.978723 (-2950 2775);
PAINT ORANGE (-2950 2775);
DISPLAY INVISIBLE (-2950 2775);
WIRE 16 -1 (-1250 3200)(-1250 3150);
WIRE 16 -1 (-1250 4350)(-1250 4200);
WIRE 16 -1 (-4500 3350)(-4500 3300);
WIRE 16 -1 (-4500 4075)(-4500 4150);
WIRE 16 -1 (-275 3200)(-275 3175);
WIRE 16 -1 (-275 3200)(-125 3200);
WIRE 16 -1 (-275 3350)(-275 3200);
WIRE 16 -1 (325 3200)(-125 3200);
WIRE 16 -1 (-125 3200)(-125 3350);
WIRE 16 -1 (325 3350)(325 3200);
WIRE 16 -1 (-300 1300)(-300 1350);
WIRE 16 -1 (-2650 4325)(-2650 4400);
WIRE 16 -1 (-3150 3050)(-3150 3175);
WIRE 16 -1 (-200 4175)(-200 4125);
WIRE 16 -1 (-300 2100)(-300 2000);
WIRE 16 -1 (325 3550)(325 3725);
WIRE 16 -1 (325 3725)(800 3725);
FORCEPROP 2 LAST SIG_NAME RST_RTCRST_N
J 0
(440 3735);
DISPLAY 0.617021 (440 3735);
PAINT ORANGE (440 3735);
WIRE 16 -1 (-125 3550)(-125 3725);
WIRE 16 -1 (-125 3725)(325 3725);
WIRE 16 -1 (-200 3725)(-125 3725);
WIRE 16 -1 (-200 3725)(-200 3925);
WIRE 16 -1 (-1825 3725)(-200 3725);
WIRE 16 -1 (-5100 2000)(-1700 2000);
WIRE 16 -1 (-5125 2125)(-5125 1450);
WIRE 16 -1 (-1675 2125)(-5125 2125);
WIRE 16 -1 (-5125 1450)(-1675 1450);
WIRE 16 -1 (-1675 1450)(-1675 2125);
WIRE 3 682 (-3150 2500)(-3150 2250);
WIRE 3 682 (-100 2500)(-3150 2500);
WIRE 3 682 (-3150 2250)(-100 2250);
WIRE 3 682 (-100 2250)(-100 2500);
WIRE 16 -1 (-2900 2100)(-2900 1500);
WIRE 16 -1 (-5100 1750)(-1700 1750);
WIRE 3 682 (-1300 3050)(-1300 3500);
WIRE 3 682 (-900 3050)(-1300 3050);
WIRE 3 682 (-900 3500)(-1300 3500);
WIRE 3 682 (-900 3500)(-900 3050);
WIRE 16 -1 (-1275 2850)(-2350 2850);
WIRE 16 -1 (-1275 2675)(-1275 2850);
WIRE 16 -1 (-2350 2850)(-2350 2675);
WIRE 16 -1 (-2350 2675)(-1275 2675);
WIRE 16 -1 (-3350 3225)(-4175 3225);
WIRE 16 -1 (-3350 3000)(-3350 3225);
WIRE 16 -1 (-4175 3225)(-4175 3000);
WIRE 16 -1 (-4175 3000)(-3350 3000);
WIRE 3 2175 (-3975 3850)(-2450 3850);
WIRE 3 2175 (-2450 3850)(-2450 3500);
WIRE 3 2175 (-3975 3850)(-3975 3500);
WIRE 3 2175 (-3975 3500)(-2450 3500);
WIRE 16 -1 (-4500 3775)(-4500 3875);
WIRE 16 -1 (-2525 3775)(-4500 3775);
FORCEPROP 2 LAST SIG_NAME PU_UV_HIGH_SET
J 0
(-3510 3785);
DISPLAY 0.638298 (-3510 3785);
PAINT ORANGE (-3510 3785);
FORCEPROP 2 LASTPROP $XRERR UNIQUE?
J 0
(-3750 3785);
DISPLAY 0.638298 (-3750 3785);
PAINT MONO (-3750 3785);
DISPLAY INVISIBLE (-3750 3785);
WIRE 16 -1 (-4125 3125)(-3400 3125);
WIRE 16 -1 (-4500 3675)(-4500 3550);
WIRE 16 -1 (-2525 3675)(-4500 3675);
FORCEPROP 2 LAST SIG_NAME PD_UV_HIGH_SET
J 0
(-3510 3685);
DISPLAY 0.638298 (-3510 3685);
PAINT ORANGE (-3510 3685);
FORCEPROP 2 LASTPROP $XRERR UNIQUE?
J 0
(-3750 3685);
DISPLAY 0.638298 (-3750 3685);
PAINT MONO (-3750 3685);
DISPLAY INVISIBLE (-3750 3685);
WIRE 16 -1 (-3350 4300)(-4175 4300);
WIRE 16 -1 (-3350 4075)(-3350 4300);
WIRE 16 -1 (-4175 4300)(-4175 4075);
WIRE 16 -1 (-4175 4075)(-3350 4075);
WIRE 16 -1 (-3950 4275)(-3950 4100);
WIRE 3 682 (-4700 3200)(-4700 4350);
WIRE 3 682 (-4250 4350)(-4700 4350);
WIRE 3 682 (-4250 3200)(-4700 3200);
WIRE 3 682 (-4250 3200)(-4250 4350);
WIRE 3 682 (-2200 3600)(-2200 3100);
WIRE 3 682 (-2100 3600)(-2200 3600);
WIRE 16 -1 (-3575 3575)(-2650 3575);
FORCEPROP 2 LAST SIG_NAME FM_UART_PRES_N
J 0
(-3510 3585);
DISPLAY 0.617021 (-3510 3585);
PAINT ORANGE (-3510 3585);
WIRE 16 -1 (-2650 3575)(-2525 3575);
WIRE 16 -1 (-2650 4125)(-2650 3575);
WIRE 16 -1 (-275 3675)(-275 3550);
WIRE 16 -1 (-1825 3675)(-275 3675);
FORCEPROP 2 LAST SIG_NAME PD_RST_RTCRST_N
J 0
(-1710 3685);
DISPLAY 0.638298 (-1710 3685);
PAINT ORANGE (-1710 3685);
FORCEPROP 2 LASTPROP $XRERR UNIQUE?
J 0
(-1950 3685);
DISPLAY 0.638298 (-1950 3685);
PAINT MONO (-1950 3685);
DISPLAY INVISIBLE (-1950 3685);
WIRE 16 -1 (-2525 3725)(-3600 3725);
FORCEPROP 2 LAST SIG_NAME UV_HIGH_SET
J 0
(-3510 3735);
DISPLAY 0.617021 (-3510 3735);
PAINT ORANGE (-3510 3735);
WIRE 16 -1 (-3575 3625)(-2525 3625);
FORCEPROP 2 LAST SIG_NAME TP_IE_DEBUG_MODE
J 0
(-3510 3635);
DISPLAY 0.617021 (-3510 3635);
PAINT ORANGE (-3510 3635);
FORCEPROP 2 LASTPROP $XRERR UNIQUE?
J 0
(-3815 3625);
DISPLAY 0.638298 (-3815 3625);
PAINT MONO (-3815 3625);
DISPLAY INVISIBLE (-3815 3625);
WIRE 16 -1 (-2325 2750)(-1300 2750);
WIRE 16 -1 (-1250 4000)(-1250 3625);
WIRE 16 -1 (-1825 3625)(-1250 3625);
FORCEPROP 2 LAST SIG_NAME PU_SPI_BMC_BT_CS0_N
J 0
(-1710 3635);
DISPLAY 0.617021 (-1710 3635);
PAINT ORANGE (-1710 3635);
FORCEPROP 2 LASTPROP $XRERR UNIQUE?
J 0
(-1950 3635);
DISPLAY 0.638298 (-1950 3635);
PAINT MONO (-1950 3635);
DISPLAY INVISIBLE (-1950 3635);
WIRE 16 -1 (-1825 3575)(-1200 3575);
FORCEPROP 2 LAST SIG_NAME SPI_BMC_BT_CS0_N
J 0
(-1710 3585);
DISPLAY 0.638298 (-1710 3585);
PAINT ORANGE (-1710 3585);
WIRE 16 -1 (-2150 2825)(-2150 2700);
WIRE 16 -1 (-800 2350)(-1600 2350);
FORCEPROP 0 LAST CDS_PHYS_NET_NAME TPM_SPI_BMC_WP_N
J 0
(-1312 2350);
PAINT MONO (-1312 2350);
DISPLAY INVISIBLE (-1312 2350);
FORCEPROP 2 LAST SIG_NAME TPM_SPI_BMC_WP_N
J 0
(-1485 2360);
DISPLAY 0.617021 (-1485 2360);
PAINT ORANGE (-1485 2360);
WIRE 16 -1 (-2550 2350)(-1800 2350);
FORCEPROP 2 LAST SIG_NAME SPI_BMC_BT_WP0_N
J 0
(-2435 2360);
DISPLAY 0.638298 (-2435 2360);
PAINT ORANGE (-2435 2360);
WIRE 16 -1 (575 4175)(575 4025);
WIRE 16 -1 (-4475 2100)(-4475 1500);
WIRE 16 -1 (-3950 3200)(-3950 3025);
WIRE 16 -1 (-300 1650)(-300 1550);
WIRE 16 -1 (-300 1800)(-300 1650);
WIRE 16 -1 (400 1650)(-300 1650);
FORCEPROP 2 LAST SIG_NAME RST_SRTCRST_N
J 0
(-60 1660);
DISPLAY 0.617021 (-60 1660);
PAINT ORANGE (-60 1660);
WIRE 16 -1 (-1825 3775)(-1050 3775);
FORCEPROP 2 LAST SIG_NAME TP_RST_RTCRST_N
J 0
(-1710 3785);
DISPLAY 0.638298 (-1710 3785);
PAINT ORANGE (-1710 3785);
FORCEPROP 2 LASTPROP $XRERR UNIQUE?
J 0
(-1020 3775);
DISPLAY 0.638298 (-1020 3775);
PAINT MONO (-1020 3775);
DISPLAY INVISIBLE (-1020 3775);
WIRE 16 -1 (-1250 3525)(-1250 3400);
WIRE 16 -1 (-1825 3525)(-1250 3525);
FORCEPROP 2 LAST SIG_NAME PD_SPI_BMC_BT_CS0_N
J 0
(-1710 3535);
DISPLAY 0.617021 (-1710 3535);
PAINT ORANGE (-1710 3535);
FORCEPROP 2 LASTPROP $XRERR UNIQUE?
J 0
(-1950 3535);
DISPLAY 0.638298 (-1950 3535);
PAINT MONO (-1950 3535);
DISPLAY INVISIBLE (-1950 3535);
WIRE 16 -1 (-3525 2100)(-3525 1500);
WIRE 16 -1 (-3150 3525)(-2525 3525);
WIRE 16 -1 (-3150 3375)(-3150 3525);
FORCEPROP 2 LAST SIG_NAME PD_IE_DEBUG_MODE
J 0
(-3110 3535);
DISPLAY 0.617021 (-3110 3535);
PAINT ORANGE (-3110 3535);
FORCEPROP 2 LASTPROP $XRERR UNIQUE?
J 0
(-3350 3535);
DISPLAY 0.638298 (-3350 3535);
PAINT MONO (-3350 3535);
DISPLAY INVISIBLE (-3350 3535);
WIRE 16 -1 (350 4100)(350 4000);
WIRE 16 -1 (350 4000)(1525 4000);
WIRE 16 -1 (350 4200)(350 4100);
WIRE 16 -1 (1525 4200)(350 4200);
WIRE 16 -1 (1525 4000)(1525 4100);
WIRE 16 -1 (350 4100)(1525 4100);
WIRE 16 -1 (1525 4100)(1525 4200);
WIRE 3 682 (-1100 3850)(-1500 3850);
WIRE 3 682 (-1500 3850)(-1500 4300);
WIRE 3 682 (-1100 4300)(-1100 3850);
WIRE 3 682 (-1100 4300)(-1500 4300);
WIRE 16 -1 (-4125 4200)(-3400 4200);
DOT 1 (-300 1650);
DOT 1 (-2650 3575);
DOT 1 (350 4100);
DOT 1 (-275 3200);
DOT 1 (1525 4100);
DOT 1 (325 3725);
DOT 1 (-125 3200);
DOT 1 (-125 3725);
DOT 1 (-200 3725);
FORCENOTE
TP FAB3 CHANGE R6W1 0803
(-5150 4550) 0;
DISPLAY LEFT (-5150 4550);
DISPLAY 1.021277 (-5150 4550);
PAINT RED (-5150 4550);
FORCENOTE
TP FAB1 MOVE RES HERE 0308
(-5175 4375) 0;
DISPLAY LEFT (-5175 4375);
DISPLAY 1.021277 (-5175 4375);
PAINT RED (-5175 4375);
FORCENOTE
3-5
(-4125 4125) 0;
DISPLAY LEFT (-4125 4125);
DISPLAY 0.617021 (-4125 4125);
PAINT PURPLE (-4125 4125);
FORCENOTE
TRIP=11.5V(DEFAULT)
(-3925 4225) 0;
DISPLAY LEFT (-3925 4225);
DISPLAY 0.617021 (-3925 4225);
PAINT PURPLE (-3925 4225);
FORCENOTE
TP FAB1 MOVE RES HERE AND POP RES 0308
(-1325 2950) 0;
DISPLAY LEFT (-1325 2950);
DISPLAY 1.021277 (-1325 2950);
PAINT RED (-1325 2950);
FORCENOTE
TP FAB1 NOPOP RES 0227
(-1100 4450) 0;
DISPLAY LEFT (-1100 4450);
DISPLAY 1.021277 (-1100 4450);
PAINT RED (-1100 4450);
FORCENOTE
TP FAB1 POP RES 0301
(-1100 4400) 0;
DISPLAY LEFT (-1100 4400);
DISPLAY 1.021277 (-1100 4400);
PAINT RED (-1100 4400);
FORCENOTE
TP FAB1 MOVE RES HERE 0308
(-1100 4350) 0;
DISPLAY LEFT (-1100 4350);
DISPLAY 1.021277 (-1100 4350);
PAINT RED (-1100 4350);
FORCENOTE
CLEAR RTC REGISTERS
(-2800 1775) 0;
DISPLAY LEFT (-2800 1775);
DISPLAY 1.021277 (-2800 1775);
PAINT PURPLE (-2800 1775);
FORCENOTE
NORMAL FUNCTIONALITY
(-2800 1900) 0;
DISPLAY LEFT (-2800 1900);
DISPLAY 1.021277 (-2800 1900);
PAINT PURPLE (-2800 1900);
FORCENOTE
2-4
(400 4125) 0;
DISPLAY LEFT (400 4125);
DISPLAY 0.617021 (400 4125);
PAINT PURPLE (400 4125);
FORCENOTE
CLEAR RTC REGISTERS
(625 4050) 0;
DISPLAY LEFT (625 4050);
DISPLAY 0.617021 (625 4050);
PAINT PURPLE (625 4050);
FORCENOTE
2-4
(-3100 1900) 0;
DISPLAY LEFT (-3100 1900);
DISPLAY 1.021277 (-3100 1900);
PAINT PURPLE (-3100 1900);
FORCENOTE
8-10
(-3100 1650) 0;
DISPLAY LEFT (-3100 1650);
DISPLAY 1.021277 (-3100 1650);
PAINT PURPLE (-3100 1650);
FORCENOTE
JUMPER LOCATION
(-5100 2025) 0;
DISPLAY LEFT (-5100 2025);
DISPLAY 1.021277 (-5100 2025);
PAINT PURPLE (-5100 2025);
FORCENOTE
9-11
(-4625 1525) 0;
DISPLAY LEFT (-4625 1525);
DISPLAY 1.021277 (-4625 1525);
PAINT PURPLE (-4625 1525);
FORCENOTE
ROOM=SB
(-5079 842) 0;
DISPLAY LEFT (-5079 842);
DISPLAY 1.191489 (-5079 842);
PAINT PURPLE (-5079 842);
FORCENOTE
3-5
(-4625 1775) 0;
DISPLAY LEFT (-4625 1775);
DISPLAY 1.021277 (-4625 1775);
PAINT PURPLE (-4625 1775);
FORCENOTE
7-9
(-4625 1650) 0;
DISPLAY LEFT (-4625 1650);
DISPLAY 1.021277 (-4625 1650);
PAINT PURPLE (-4625 1650);
FORCENOTE
1-3
(-4625 1900) 0;
DISPLAY LEFT (-4625 1900);
DISPLAY 1.021277 (-4625 1900);
PAINT PURPLE (-4625 1900);
FORCENOTE
10-12
(-3100 1525) 0;
DISPLAY LEFT (-3100 1525);
DISPLAY 1.021277 (-3100 1525);
PAINT PURPLE (-3100 1525);
FORCENOTE
4-6
(-3100 1775) 0;
DISPLAY LEFT (-3100 1775);
DISPLAY 1.021277 (-3100 1775);
PAINT PURPLE (-3100 1775);
FORCENOTE
8-10
(-2300 2775) 0;
DISPLAY LEFT (-2300 2775);
DISPLAY 0.617021 (-2300 2775);
PAINT PURPLE (-2300 2775);
FORCENOTE
10-12
(-2300 2700) 0;
DISPLAY LEFT (-2300 2700);
DISPLAY 0.617021 (-2300 2700);
PAINT PURPLE (-2300 2700);
FORCENOTE
NORMAL RTC RESET (DEFAULT)
(625 4125) 0;
DISPLAY LEFT (625 4125);
DISPLAY 0.617021 (625 4125);
PAINT PURPLE (625 4125);
FORCENOTE
4-6
(400 4050) 0;
DISPLAY LEFT (400 4050);
DISPLAY 0.617021 (400 4050);
PAINT PURPLE (400 4050);
FORCENOTE
TP FAB1 NOPOP RES 0301
(-1325 3000) 0;
DISPLAY LEFT (-1325 3000);
DISPLAY 1.021277 (-1325 3000);
PAINT RED (-1325 3000);
FORCENOTE
7-9
(-4125 3150) 0;
DISPLAY LEFT (-4125 3150);
DISPLAY 0.617021 (-4125 3150);
PAINT PURPLE (-4125 3150);
FORCENOTE
1-3
(-4125 4225) 0;
DISPLAY LEFT (-4125 4225);
DISPLAY 0.617021 (-4125 4225);
PAINT PURPLE (-4125 4225);
FORCENOTE
TRIP=11V
(-3925 4125) 0;
DISPLAY LEFT (-3925 4125);
DISPLAY 0.617021 (-3925 4125);
PAINT PURPLE (-3925 4125);
FORCENOTE
9-11
(-4125 3050) 0;
DISPLAY LEFT (-4125 3050);
DISPLAY 0.617021 (-4125 3050);
PAINT PURPLE (-4125 3050);
FORCENOTE
TP FAB1 J9G1 PIN 3&5 RESERVE TSET POINT 1203
(-3975 3925) 0;
DISPLAY LEFT (-3975 3925);
DISPLAY 1.021277 (-3975 3925);
PAINT RED (-3975 3925);
FORCENOTE
TP FAB1 RECONNECT PIN 1, 3, 5 0308
(-3975 3875) 0;
DISPLAY LEFT (-3975 3875);
DISPLAY 1.021277 (-3975 3875);
PAINT RED (-3975 3875);
FORCENOTE
NORMAL<DEFAULT>
(-3925 3150) 0;
DISPLAY LEFT (-3925 3150);
DISPLAY 0.617021 (-3925 3150);
PAINT PURPLE (-3925 3150);
FORCENOTE
SMBUS UART NOT PRESENT
(-3925 3050) 0;
DISPLAY LEFT (-3925 3050);
DISPLAY 0.617021 (-3925 3050);
PAINT PURPLE (-3925 3050);
FORCENOTE
BMC DISABLE
(-2100 2700) 0;
DISPLAY LEFT (-2100 2700);
DISPLAY 0.617021 (-2100 2700);
PAINT PURPLE (-2100 2700);
FORCENOTE
BMC ENABLE (DEFAULT)
(-2100 2775) 0;
DISPLAY LEFT (-2100 2775);
DISPLAY 0.617021 (-2100 2775);
PAINT PURPLE (-2100 2775);
FORCENOTE
SMBUS UART NOT PRESENT
(-4425 1525) 0;
DISPLAY LEFT (-4425 1525);
DISPLAY 1.021277 (-4425 1525);
PAINT PURPLE (-4425 1525);
FORCENOTE
NORMAL FUNCTIONALITY
(-4425 1650) 0;
DISPLAY LEFT (-4425 1650);
DISPLAY 1.021277 (-4425 1650);
PAINT PURPLE (-4425 1650);
FORCENOTE
TP FAB1 ADD RES 0308
(-3125 2200) 0;
DISPLAY LEFT (-3125 2200);
DISPLAY 1.021277 (-3125 2200);
PAINT RED (-3125 2200);
FORCENOTE
SYSTEM BEHAVIOR
(-2800 2025) 0;
DISPLAY LEFT (-2800 2025);
DISPLAY 1.021277 (-2800 2025);
PAINT PURPLE (-2800 2025);
FORCENOTE
JUMPER LOCATION
(-3500 2025) 0;
DISPLAY LEFT (-3500 2025);
DISPLAY 1.021277 (-3500 2025);
PAINT PURPLE (-3500 2025);
FORCENOTE
SYSTEM BEHAVIOR
(-4425 2025) 0;
DISPLAY LEFT (-4425 2025);
DISPLAY 1.021277 (-4425 2025);
PAINT PURPLE (-4425 2025);
FORCENOTE
TRIP=11V
(-4425 1775) 0;
DISPLAY LEFT (-4425 1775);
DISPLAY 1.021277 (-4425 1775);
PAINT PURPLE (-4425 1775);
FORCENOTE
BMC ENABLE (DEFAULT)
(-2800 1650) 0;
DISPLAY LEFT (-2800 1650);
DISPLAY 1.021277 (-2800 1650);
PAINT PURPLE (-2800 1650);
FORCENOTE
BMC DISABLE
(-2800 1525) 0;
DISPLAY LEFT (-2800 1525);
DISPLAY 1.021277 (-2800 1525);
PAINT PURPLE (-2800 1525);
FORCENOTE
TRIP=11.5V (DEAULT)
(-4425 1900) 0;
DISPLAY LEFT (-4425 1900);
DISPLAY 1.021277 (-4425 1900);
PAINT PURPLE (-4425 1900);
FORCENOTE
TP FAB1 CHANGE JUMPER 8, 10, 12 FUNCTION 0308
(-1875 2850) 0;
DISPLAY LEFT (-1875 2850);
DISPLAY 1.021277 (-1875 2850);
PAINT RED (-1875 2850);
QUIT
